(kicad_sch
	(version 20250114)
	(generator "eeschema")
	(generator_version "9.0")
	(paper "A3")
	(title_block
		(title "Artix - Datacenter Secure Control Module (DC-SCM)")
		(date "2024-11-06")
		(rev "1.1.3")
	)
	(text "1.8V/3A"
		(exclude_from_sim no)
		(at 395.605 82.55 0)
		(effects
			(font
				(size 1.27 1.27)
			)
			(justify left bottom)
		)
	)
	(text "Delay capacitor calculated \nas 0->1.22V change via 100k to 5V\n(now set as 0.2 - 0.3s delay)"
		(exclude_from_sim no)
		(at 22.225 209.55 0)
		(effects
			(font
				(size 1.27 1.27)
			)
			(justify left bottom)
		)
	)
	(text "3.3V/3A"
		(exclude_from_sim no)
		(at 395.605 38.1 0)
		(effects
			(font
				(size 1.27 1.27)
			)
			(justify left bottom)
		)
	)
	(text "1.0V/3A"
		(exclude_from_sim no)
		(at 395.605 171.45 0)
		(effects
			(font
				(size 1.27 1.27)
			)
			(justify left bottom)
		)
	)
	(text "1V8 supply"
		(exclude_from_sim no)
		(at 330.2 66.675 0)
		(effects
			(font
				(size 2 2)
				(thickness 0.5994)
				(bold yes)
			)
			(justify left bottom)
		)
	)
	(text "1V0 supply"
		(exclude_from_sim no)
		(at 330.2 155.575 0)
		(effects
			(font
				(size 2 2)
				(thickness 0.5994)
				(bold yes)
			)
			(justify left bottom)
		)
	)
	(text "1.35V/3A"
		(exclude_from_sim no)
		(at 395.605 127 0)
		(effects
			(font
				(size 1.27 1.27)
			)
			(justify left bottom)
		)
	)
	(text "1V2 supply"
		(exclude_from_sim no)
		(at 329.565 200.025 0)
		(effects
			(font
				(size 2 2)
				(thickness 0.5994)
				(bold yes)
			)
			(justify left bottom)
		)
	)
	(text "To DC-SCM connector"
		(exclude_from_sim no)
		(at 45.72 124.46 0)
		(effects
			(font
				(size 1.27 1.27)
			)
			(justify left bottom)
		)
	)
	(text "3v3 required by I3C translator"
		(exclude_from_sim no)
		(at 200.025 150.495 0)
		(effects
			(font
				(size 1.27 1.27)
			)
			(justify left bottom)
		)
	)
	(text "STEP1: FPGA VCCINT (1V0)\nSTEP2: FPGA VCCAUX (1V8)\nSTEP3: FPGA VCCIO (3V3), HPM reset is de-asserted\nSTEP4: HPM boots"
		(exclude_from_sim no)
		(at 114.3 213.36 0)
		(effects
			(font
				(size 1.27 1.27)
			)
			(justify left bottom)
		)
	)
	(text "DC-SCM 12V supply"
		(exclude_from_sim no)
		(at 19.685 22.225 0)
		(effects
			(font
				(size 2 2)
				(thickness 0.5994)
				(bold yes)
			)
			(justify left bottom)
		)
	)
	(text "Power sequencer"
		(exclude_from_sim no)
		(at 20.32 177.165 0)
		(effects
			(font
				(size 2 2)
				(thickness 0.4)
				(bold yes)
			)
			(justify left bottom)
		)
	)
	(text "MainSupply (5V 5A)"
		(exclude_from_sim no)
		(at 95.885 44.45 0)
		(effects
			(font
				(size 2 2)
				(thickness 0.5994)
				(bold yes)
			)
			(justify left bottom)
		)
	)
	(text "1V35 supply"
		(exclude_from_sim no)
		(at 330.2 111.125 0)
		(effects
			(font
				(size 2 2)
				(thickness 0.5994)
				(bold yes)
			)
			(justify left bottom)
		)
	)
	(text "PWR_LED Indicators"
		(exclude_from_sim no)
		(at 218.44 22.225 0)
		(effects
			(font
				(size 2 2)
				(thickness 0.5994)
				(bold yes)
			)
			(justify left bottom)
		)
	)
	(text "3V3 supply"
		(exclude_from_sim no)
		(at 330.2 22.225 0)
		(effects
			(font
				(size 2 2)
				(thickness 0.5994)
				(bold yes)
			)
			(justify left bottom)
		)
	)
	(text "1.2V/3A"
		(exclude_from_sim no)
		(at 396.24 215.9 0)
		(effects
			(font
				(size 1.27 1.27)
			)
			(justify left bottom)
		)
	)
	(text "Battery connector"
		(exclude_from_sim no)
		(at 25.4 111.76 0)
		(effects
			(font
				(size 2 2)
				(thickness 0.4)
				(bold yes)
			)
			(justify left bottom)
		)
	)
	(text "External 12V supply"
		(exclude_from_sim no)
		(at 19.685 45.085 0)
		(effects
			(font
				(size 2 2)
				(thickness 0.5994)
				(bold yes)
			)
			(justify left bottom)
		)
	)
	(junction
		(at 353.06 123.19)
		(diameter 0)
		(color 0 0 0 0)
	)
	(junction
		(at 345.44 91.44)
		(diameter 0)
		(color 0 0 0 0)
	)
	(junction
		(at 369.57 123.19)
		(diameter 0)
		(color 0 0 0 0)
	)
	(junction
		(at 360.68 78.74)
		(diameter 0)
		(color 0 0 0 0)
	)
	(junction
		(at 353.06 167.64)
		(diameter 0)
		(color 0 0 0 0)
	)
	(junction
		(at 154.94 81.28)
		(diameter 0)
		(color 0 0 0 0)
	)
	(junction
		(at 377.19 78.74)
		(diameter 0)
		(color 0 0 0 0)
	)
	(junction
		(at 129.54 106.68)
		(diameter 0)
		(color 0 0 0 0)
	)
	(junction
		(at 62.23 182.88)
		(diameter 0)
		(color 0 0 0 0)
	)
	(junction
		(at 113.03 196.85)
		(diameter 0)
		(color 0 0 0 0)
	)
	(junction
		(at 224.79 104.14)
		(diameter 0)
		(color 0 0 0 0)
	)
	(junction
		(at 345.44 135.89)
		(diameter 0)
		(color 0 0 0 0)
	)
	(junction
		(at 360.68 175.26)
		(diameter 0)
		(color 0 0 0 0)
	)
	(junction
		(at 353.06 86.36)
		(diameter 0)
		(color 0 0 0 0)
	)
	(junction
		(at 81.28 54.61)
		(diameter 0)
		(color 0 0 0 0)
	)
	(junction
		(at 345.44 224.79)
		(diameter 0)
		(color 0 0 0 0)
	)
	(junction
		(at 377.19 212.09)
		(diameter 0)
		(color 0 0 0 0)
	)
	(junction
		(at 393.7 212.09)
		(diameter 0)
		(color 0 0 0 0)
	)
	(junction
		(at 360.68 130.81)
		(diameter 0)
		(color 0 0 0 0)
	)
	(junction
		(at 393.7 34.29)
		(diameter 0)
		(color 0 0 0 0)
	)
	(junction
		(at 80.01 92.71)
		(diameter 0)
		(color 0 0 0 0)
	)
	(junction
		(at 121.92 81.28)
		(diameter 0)
		(color 0 0 0 0)
	)
	(junction
		(at 316.23 201.93)
		(diameter 0)
		(color 0 0 0 0)
	)
	(junction
		(at 316.23 157.48)
		(diameter 0)
		(color 0 0 0 0)
	)
	(junction
		(at 345.44 180.34)
		(diameter 0)
		(color 0 0 0 0)
	)
	(junction
		(at 369.57 34.29)
		(diameter 0)
		(color 0 0 0 0)
	)
	(junction
		(at 393.7 78.74)
		(diameter 0)
		(color 0 0 0 0)
	)
	(junction
		(at 87.63 54.61)
		(diameter 0)
		(color 0 0 0 0)
	)
	(junction
		(at 64.77 54.61)
		(diameter 0)
		(color 0 0 0 0)
	)
	(junction
		(at 224.79 134.62)
		(diameter 0)
		(color 0 0 0 0)
	)
	(junction
		(at 369.57 212.09)
		(diameter 0)
		(color 0 0 0 0)
	)
	(junction
		(at 120.65 199.39)
		(diameter 0)
		(color 0 0 0 0)
	)
	(junction
		(at 345.44 46.99)
		(diameter 0)
		(color 0 0 0 0)
	)
	(junction
		(at 39.37 128.27)
		(diameter 0)
		(color 0 0 0 0)
	)
	(junction
		(at 93.98 54.61)
		(diameter 0)
		(color 0 0 0 0)
	)
	(junction
		(at 369.57 78.74)
		(diameter 0)
		(color 0 0 0 0)
	)
	(junction
		(at 74.93 54.61)
		(diameter 0)
		(color 0 0 0 0)
	)
	(junction
		(at 105.41 182.88)
		(diameter 0)
		(color 0 0 0 0)
	)
	(junction
		(at 226.06 44.45)
		(diameter 0)
		(color 0 0 0 0)
	)
	(junction
		(at 316.23 113.03)
		(diameter 0)
		(color 0 0 0 0)
	)
	(junction
		(at 165.1 81.28)
		(diameter 0)
		(color 0 0 0 0)
	)
	(junction
		(at 360.68 123.19)
		(diameter 0)
		(color 0 0 0 0)
	)
	(junction
		(at 226.06 72.39)
		(diameter 0)
		(color 0 0 0 0)
	)
	(junction
		(at 44.45 54.61)
		(diameter 0)
		(color 0 0 0 0)
	)
	(junction
		(at 377.19 123.19)
		(diameter 0)
		(color 0 0 0 0)
	)
	(junction
		(at 360.68 41.91)
		(diameter 0)
		(color 0 0 0 0)
	)
	(junction
		(at 113.03 182.88)
		(diameter 0)
		(color 0 0 0 0)
	)
	(junction
		(at 353.06 212.09)
		(diameter 0)
		(color 0 0 0 0)
	)
	(junction
		(at 353.06 78.74)
		(diameter 0)
		(color 0 0 0 0)
	)
	(junction
		(at 105.41 194.31)
		(diameter 0)
		(color 0 0 0 0)
	)
	(junction
		(at 353.06 34.29)
		(diameter 0)
		(color 0 0 0 0)
	)
	(junction
		(at 353.06 41.91)
		(diameter 0)
		(color 0 0 0 0)
	)
	(junction
		(at 88.9 92.71)
		(diameter 0)
		(color 0 0 0 0)
	)
	(junction
		(at 360.68 212.09)
		(diameter 0)
		(color 0 0 0 0)
	)
	(junction
		(at 36.83 62.23)
		(diameter 0)
		(color 0 0 0 0)
	)
	(junction
		(at 78.74 182.88)
		(diameter 0)
		(color 0 0 0 0)
	)
	(junction
		(at 393.7 167.64)
		(diameter 0)
		(color 0 0 0 0)
	)
	(junction
		(at 123.19 92.71)
		(diameter 0)
		(color 0 0 0 0)
	)
	(junction
		(at 71.12 54.61)
		(diameter 0)
		(color 0 0 0 0)
	)
	(junction
		(at 353.06 175.26)
		(diameter 0)
		(color 0 0 0 0)
	)
	(junction
		(at 393.7 123.19)
		(diameter 0)
		(color 0 0 0 0)
	)
	(junction
		(at 377.19 167.64)
		(diameter 0)
		(color 0 0 0 0)
	)
	(junction
		(at 223.52 167.64)
		(diameter 0)
		(color 0 0 0 0)
	)
	(junction
		(at 171.45 81.28)
		(diameter 0)
		(color 0 0 0 0)
	)
	(junction
		(at 360.68 167.64)
		(diameter 0)
		(color 0 0 0 0)
	)
	(junction
		(at 353.06 130.81)
		(diameter 0)
		(color 0 0 0 0)
	)
	(junction
		(at 316.23 68.58)
		(diameter 0)
		(color 0 0 0 0)
	)
	(junction
		(at 360.68 86.36)
		(diameter 0)
		(color 0 0 0 0)
	)
	(junction
		(at 316.23 24.13)
		(diameter 0)
		(color 0 0 0 0)
	)
	(junction
		(at 353.06 219.71)
		(diameter 0)
		(color 0 0 0 0)
	)
	(junction
		(at 177.8 81.28)
		(diameter 0)
		(color 0 0 0 0)
	)
	(junction
		(at 377.19 34.29)
		(diameter 0)
		(color 0 0 0 0)
	)
	(junction
		(at 360.68 34.29)
		(diameter 0)
		(color 0 0 0 0)
	)
	(junction
		(at 195.58 81.28)
		(diameter 0)
		(color 0 0 0 0)
	)
	(junction
		(at 36.83 59.69)
		(diameter 0)
		(color 0 0 0 0)
	)
	(junction
		(at 369.57 167.64)
		(diameter 0)
		(color 0 0 0 0)
	)
	(junction
		(at 62.23 196.85)
		(diameter 0)
		(color 0 0 0 0)
	)
	(junction
		(at 39.37 125.73)
		(diameter 0)
		(color 0 0 0 0)
	)
	(junction
		(at 135.89 81.28)
		(diameter 0)
		(color 0 0 0 0)
	)
	(junction
		(at 360.68 219.71)
		(diameter 0)
		(color 0 0 0 0)
	)
	(junction
		(at 154.94 95.25)
		(diameter 0)
		(color 0 0 0 0)
	)
	(junction
		(at 78.74 194.31)
		(diameter 0)
		(color 0 0 0 0)
	)
	(junction
		(at 54.61 54.61)
		(diameter 0)
		(color 0 0 0 0)
	)
	(no_connect
		(at 323.85 46.99)
	)
	(wire
		(pts
			(xy 300.99 218.44) (xy 313.69 218.44)
		)
		(stroke
			(width 0)
			(type default)
		)
	)
	(wire
		(pts
			(xy 360.68 167.64) (xy 369.57 167.64)
		)
		(stroke
			(width 0)
			(type default)
		)
	)
	(wire
		(pts
			(xy 322.58 167.64) (xy 323.85 167.64)
		)
		(stroke
			(width 0)
			(type default)
		)
	)
	(wire
		(pts
			(xy 135.89 81.28) (xy 139.7 81.28)
		)
		(stroke
			(width 0)
			(type default)
		)
	)
	(wire
		(pts
			(xy 35.56 57.15) (xy 36.83 57.15)
		)
		(stroke
			(width 0)
			(type default)
		)
	)
	(wire
		(pts
			(xy 224.79 102.87) (xy 224.79 104.14)
		)
		(stroke
			(width 0)
			(type default)
		)
	)
	(wire
		(pts
			(xy 316.23 68.58) (xy 316.23 69.85)
		)
		(stroke
			(width 0)
			(type default)
		)
	)
	(wire
		(pts
			(xy 35.56 59.69) (xy 36.83 59.69)
		)
		(stroke
			(width 0)
			(type default)
		)
	)
	(wire
		(pts
			(xy 105.41 182.88) (xy 113.03 182.88)
		)
		(stroke
			(width 0)
			(type default)
		)
	)
	(wire
		(pts
			(xy 353.06 78.74) (xy 360.68 78.74)
		)
		(stroke
			(width 0)
			(type default)
		)
	)
	(wire
		(pts
			(xy 369.57 167.64) (xy 377.19 167.64)
		)
		(stroke
			(width 0)
			(type default)
		)
	)
	(wire
		(pts
			(xy 360.68 212.09) (xy 360.68 213.36)
		)
		(stroke
			(width 0)
			(type default)
		)
	)
	(wire
		(pts
			(xy 38.1 128.27) (xy 39.37 128.27)
		)
		(stroke
			(width 0)
			(type default)
		)
	)
	(wire
		(pts
			(xy 82.55 194.31) (xy 78.74 194.31)
		)
		(stroke
			(width 0)
			(type default)
		)
	)
	(wire
		(pts
			(xy 346.71 78.74) (xy 344.17 78.74)
		)
		(stroke
			(width 0)
			(type default)
		)
	)
	(wire
		(pts
			(xy 55.88 182.88) (xy 62.23 182.88)
		)
		(stroke
			(width 0)
			(type default)
		)
	)
	(wire
		(pts
			(xy 236.22 187.96) (xy 236.22 189.23)
		)
		(stroke
			(width 0)
			(type default)
		)
	)
	(wire
		(pts
			(xy 44.45 54.61) (xy 54.61 54.61)
		)
		(stroke
			(width 0)
			(type default)
		)
	)
	(polyline
		(pts
			(xy 12.7 213.36) (xy 12.7 214.63)
		)
		(stroke
			(width 0)
			(type default)
		)
	)
	(wire
		(pts
			(xy 377.19 34.29) (xy 383.54 34.29)
		)
		(stroke
			(width 0)
			(type default)
		)
	)
	(wire
		(pts
			(xy 33.02 29.21) (xy 44.45 29.21)
		)
		(stroke
			(width 0)
			(type default)
		)
	)
	(wire
		(pts
			(xy 35.56 54.61) (xy 44.45 54.61)
		)
		(stroke
			(width 0)
			(type default)
		)
	)
	(wire
		(pts
			(xy 369.57 212.09) (xy 377.19 212.09)
		)
		(stroke
			(width 0)
			(type default)
		)
	)
	(wire
		(pts
			(xy 237.49 93.98) (xy 247.65 93.98)
		)
		(stroke
			(width 0)
			(type default)
		)
	)
	(wire
		(pts
			(xy 351.79 34.29) (xy 353.06 34.29)
		)
		(stroke
			(width 0)
			(type default)
		)
	)
	(wire
		(pts
			(xy 360.68 85.09) (xy 360.68 86.36)
		)
		(stroke
			(width 0)
			(type default)
		)
	)
	(wire
		(pts
			(xy 236.22 157.48) (xy 247.65 157.48)
		)
		(stroke
			(width 0)
			(type default)
		)
	)
	(wire
		(pts
			(xy 49.53 29.21) (xy 71.12 29.21)
		)
		(stroke
			(width 0)
			(type default)
		)
	)
	(wire
		(pts
			(xy 237.49 124.46) (xy 247.65 124.46)
		)
		(stroke
			(width 0)
			(type default)
		)
	)
	(wire
		(pts
			(xy 318.77 40.64) (xy 323.85 40.64)
		)
		(stroke
			(width 0)
			(type default)
		)
	)
	(wire
		(pts
			(xy 121.92 81.28) (xy 135.89 81.28)
		)
		(stroke
			(width 0)
			(type default)
		)
	)
	(wire
		(pts
			(xy 345.44 46.99) (xy 345.44 48.26)
		)
		(stroke
			(width 0)
			(type default)
		)
	)
	(wire
		(pts
			(xy 39.37 125.73) (xy 39.37 128.27)
		)
		(stroke
			(width 0)
			(type default)
		)
	)
	(wire
		(pts
			(xy 252.73 124.46) (xy 260.35 124.46)
		)
		(stroke
			(width 0)
			(type default)
		)
	)
	(wire
		(pts
			(xy 346.71 85.09) (xy 344.17 85.09)
		)
		(stroke
			(width 0)
			(type default)
		)
	)
	(wire
		(pts
			(xy 93.98 73.66) (xy 93.98 54.61)
		)
		(stroke
			(width 0)
			(type default)
		)
	)
	(wire
		(pts
			(xy 346.71 130.81) (xy 353.06 130.81)
		)
		(stroke
			(width 0)
			(type default)
		)
	)
	(wire
		(pts
			(xy 388.62 212.09) (xy 393.7 212.09)
		)
		(stroke
			(width 0)
			(type default)
		)
	)
	(wire
		(pts
			(xy 237.49 93.98) (xy 237.49 95.25)
		)
		(stroke
			(width 0)
			(type default)
		)
	)
	(polyline
		(pts
			(xy 68.58 198.12) (xy 68.58 214.63)
		)
		(stroke
			(width 0)
			(type dash)
		)
	)
	(wire
		(pts
			(xy 322.58 212.09) (xy 322.58 201.93)
		)
		(stroke
			(width 0)
			(type default)
		)
	)
	(wire
		(pts
			(xy 322.58 157.48) (xy 316.23 157.48)
		)
		(stroke
			(width 0)
			(type default)
		)
	)
	(wire
		(pts
			(xy 212.09 72.39) (xy 226.06 72.39)
		)
		(stroke
			(width 0)
			(type default)
		)
	)
	(wire
		(pts
			(xy 46.99 196.85) (xy 62.23 196.85)
		)
		(stroke
			(width 0)
			(type default)
		)
	)
	(wire
		(pts
			(xy 64.77 54.61) (xy 71.12 54.61)
		)
		(stroke
			(width 0)
			(type default)
		)
	)
	(wire
		(pts
			(xy 345.44 222.25) (xy 345.44 224.79)
		)
		(stroke
			(width 0)
			(type default)
		)
	)
	(wire
		(pts
			(xy 346.71 86.36) (xy 346.71 85.09)
		)
		(stroke
			(width 0)
			(type default)
		)
	)
	(wire
		(pts
			(xy 369.57 34.29) (xy 369.57 35.56)
		)
		(stroke
			(width 0)
			(type default)
		)
	)
	(wire
		(pts
			(xy 344.17 133.35) (xy 345.44 133.35)
		)
		(stroke
			(width 0)
			(type default)
		)
	)
	(wire
		(pts
			(xy 353.06 123.19) (xy 353.06 124.46)
		)
		(stroke
			(width 0)
			(type default)
		)
	)
	(wire
		(pts
			(xy 346.71 175.26) (xy 353.06 175.26)
		)
		(stroke
			(width 0)
			(type default)
		)
	)
	(wire
		(pts
			(xy 322.58 212.09) (xy 323.85 212.09)
		)
		(stroke
			(width 0)
			(type default)
		)
	)
	(wire
		(pts
			(xy 35.56 62.23) (xy 36.83 62.23)
		)
		(stroke
			(width 0)
			(type default)
		)
	)
	(wire
		(pts
			(xy 345.44 224.79) (xy 345.44 226.06)
		)
		(stroke
			(width 0)
			(type default)
		)
	)
	(wire
		(pts
			(xy 346.71 41.91) (xy 353.06 41.91)
		)
		(stroke
			(width 0)
			(type default)
		)
	)
	(wire
		(pts
			(xy 388.62 78.74) (xy 393.7 78.74)
		)
		(stroke
			(width 0)
			(type default)
		)
	)
	(wire
		(pts
			(xy 346.71 34.29) (xy 344.17 34.29)
		)
		(stroke
			(width 0)
			(type default)
		)
	)
	(wire
		(pts
			(xy 369.57 123.19) (xy 377.19 123.19)
		)
		(stroke
			(width 0)
			(type default)
		)
	)
	(wire
		(pts
			(xy 129.54 99.06) (xy 129.54 100.33)
		)
		(stroke
			(width 0)
			(type default)
		)
	)
	(wire
		(pts
			(xy 353.06 167.64) (xy 353.06 168.91)
		)
		(stroke
			(width 0)
			(type default)
		)
	)
	(wire
		(pts
			(xy 44.45 54.61) (xy 44.45 58.42)
		)
		(stroke
			(width 0)
			(type default)
		)
	)
	(wire
		(pts
			(xy 95.25 76.2) (xy 87.63 76.2)
		)
		(stroke
			(width 0)
			(type default)
		)
	)
	(wire
		(pts
			(xy 129.54 106.68) (xy 123.19 106.68)
		)
		(stroke
			(width 0)
			(type default)
		)
	)
	(wire
		(pts
			(xy 322.58 24.13) (xy 316.23 24.13)
		)
		(stroke
			(width 0)
			(type default)
		)
	)
	(wire
		(pts
			(xy 113.03 182.88) (xy 120.65 182.88)
		)
		(stroke
			(width 0)
			(type default)
		)
	)
	(wire
		(pts
			(xy 369.57 212.09) (xy 369.57 213.36)
		)
		(stroke
			(width 0)
			(type default)
		)
	)
	(wire
		(pts
			(xy 177.8 81.28) (xy 185.42 81.28)
		)
		(stroke
			(width 0)
			(type default)
		)
	)
	(wire
		(pts
			(xy 360.68 167.64) (xy 360.68 168.91)
		)
		(stroke
			(width 0)
			(type default)
		)
	)
	(wire
		(pts
			(xy 195.58 81.28) (xy 200.66 81.28)
		)
		(stroke
			(width 0)
			(type default)
		)
	)
	(wire
		(pts
			(xy 393.7 212.09) (xy 396.24 212.09)
		)
		(stroke
			(width 0)
			(type default)
		)
	)
	(wire
		(pts
			(xy 353.06 34.29) (xy 353.06 35.56)
		)
		(stroke
			(width 0)
			(type default)
		)
	)
	(wire
		(pts
			(xy 38.1 123.19) (xy 39.37 123.19)
		)
		(stroke
			(width 0)
			(type default)
		)
	)
	(wire
		(pts
			(xy 316.23 24.13) (xy 316.23 25.4)
		)
		(stroke
			(width 0)
			(type default)
		)
	)
	(wire
		(pts
			(xy 322.58 78.74) (xy 323.85 78.74)
		)
		(stroke
			(width 0)
			(type default)
		)
	)
	(wire
		(pts
			(xy 351.79 212.09) (xy 353.06 212.09)
		)
		(stroke
			(width 0)
			(type default)
		)
	)
	(wire
		(pts
			(xy 78.74 182.88) (xy 105.41 182.88)
		)
		(stroke
			(width 0)
			(type default)
		)
	)
	(wire
		(pts
			(xy 345.44 44.45) (xy 345.44 46.99)
		)
		(stroke
			(width 0)
			(type default)
		)
	)
	(wire
		(pts
			(xy 82.55 199.39) (xy 78.74 199.39)
		)
		(stroke
			(width 0)
			(type default)
		)
	)
	(wire
		(pts
			(xy 88.9 83.82) (xy 88.9 85.09)
		)
		(stroke
			(width 0)
			(type default)
		)
	)
	(wire
		(pts
			(xy 105.41 194.31) (xy 137.16 194.31)
		)
		(stroke
			(width 0)
			(type default)
		)
	)
	(wire
		(pts
			(xy 78.74 182.88) (xy 78.74 194.31)
		)
		(stroke
			(width 0)
			(type default)
		)
	)
	(polyline
		(pts
			(xy 68.58 214.63) (xy 21.59 214.63)
		)
		(stroke
			(width 0)
			(type dash)
		)
	)
	(wire
		(pts
			(xy 346.71 41.91) (xy 346.71 40.64)
		)
		(stroke
			(width 0)
			(type default)
		)
	)
	(wire
		(pts
			(xy 220.98 167.64) (xy 223.52 167.64)
		)
		(stroke
			(width 0)
			(type default)
		)
	)
	(wire
		(pts
			(xy 353.06 41.91) (xy 353.06 40.64)
		)
		(stroke
			(width 0)
			(type default)
		)
	)
	(wire
		(pts
			(xy 316.23 113.03) (xy 316.23 114.3)
		)
		(stroke
			(width 0)
			(type default)
		)
	)
	(wire
		(pts
			(xy 360.68 78.74) (xy 360.68 80.01)
		)
		(stroke
			(width 0)
			(type default)
		)
	)
	(wire
		(pts
			(xy 80.01 92.71) (xy 88.9 92.71)
		)
		(stroke
			(width 0)
			(type default)
		)
	)
	(wire
		(pts
			(xy 353.06 78.74) (xy 353.06 80.01)
		)
		(stroke
			(width 0)
			(type default)
		)
	)
	(wire
		(pts
			(xy 369.57 78.74) (xy 369.57 80.01)
		)
		(stroke
			(width 0)
			(type default)
		)
	)
	(wire
		(pts
			(xy 377.19 212.09) (xy 377.19 213.36)
		)
		(stroke
			(width 0)
			(type default)
		)
	)
	(wire
		(pts
			(xy 344.17 135.89) (xy 345.44 135.89)
		)
		(stroke
			(width 0)
			(type default)
		)
	)
	(wire
		(pts
			(xy 120.65 76.2) (xy 121.92 76.2)
		)
		(stroke
			(width 0)
			(type default)
		)
	)
	(wire
		(pts
			(xy 71.12 54.61) (xy 74.93 54.61)
		)
		(stroke
			(width 0)
			(type default)
		)
	)
	(wire
		(pts
			(xy 177.8 81.28) (xy 177.8 82.55)
		)
		(stroke
			(width 0)
			(type default)
		)
	)
	(wire
		(pts
			(xy 346.71 218.44) (xy 344.17 218.44)
		)
		(stroke
			(width 0)
			(type default)
		)
	)
	(wire
		(pts
			(xy 344.17 91.44) (xy 345.44 91.44)
		)
		(stroke
			(width 0)
			(type default)
		)
	)
	(wire
		(pts
			(xy 226.06 43.18) (xy 226.06 44.45)
		)
		(stroke
			(width 0)
			(type default)
		)
	)
	(wire
		(pts
			(xy 154.94 93.98) (xy 154.94 95.25)
		)
		(stroke
			(width 0)
			(type default)
		)
	)
	(wire
		(pts
			(xy 360.68 212.09) (xy 369.57 212.09)
		)
		(stroke
			(width 0)
			(type default)
		)
	)
	(wire
		(pts
			(xy 360.68 219.71) (xy 360.68 218.44)
		)
		(stroke
			(width 0)
			(type default)
		)
	)
	(wire
		(pts
			(xy 223.52 160.02) (xy 223.52 161.29)
		)
		(stroke
			(width 0)
			(type default)
		)
	)
	(wire
		(pts
			(xy 62.23 196.85) (xy 82.55 196.85)
		)
		(stroke
			(width 0)
			(type default)
		)
	)
	(wire
		(pts
			(xy 113.03 182.88) (xy 113.03 184.15)
		)
		(stroke
			(width 0)
			(type default)
		)
	)
	(wire
		(pts
			(xy 393.7 78.74) (xy 396.24 78.74)
		)
		(stroke
			(width 0)
			(type default)
		)
	)
	(wire
		(pts
			(xy 238.76 62.23) (xy 247.65 62.23)
		)
		(stroke
			(width 0)
			(type default)
		)
	)
	(wire
		(pts
			(xy 322.58 123.19) (xy 322.58 113.03)
		)
		(stroke
			(width 0)
			(type default)
		)
	)
	(wire
		(pts
			(xy 81.28 58.42) (xy 81.28 54.61)
		)
		(stroke
			(width 0)
			(type default)
		)
	)
	(wire
		(pts
			(xy 99.06 201.93) (xy 101.6 201.93)
		)
		(stroke
			(width 0)
			(type default)
		)
	)
	(wire
		(pts
			(xy 377.19 78.74) (xy 383.54 78.74)
		)
		(stroke
			(width 0)
			(type default)
		)
	)
	(wire
		(pts
			(xy 36.83 59.69) (xy 36.83 62.23)
		)
		(stroke
			(width 0)
			(type default)
		)
	)
	(wire
		(pts
			(xy 344.17 88.9) (xy 345.44 88.9)
		)
		(stroke
			(width 0)
			(type default)
		)
	)
	(wire
		(pts
			(xy 353.06 123.19) (xy 360.68 123.19)
		)
		(stroke
			(width 0)
			(type default)
		)
	)
	(wire
		(pts
			(xy 265.43 187.96) (xy 266.7 187.96)
		)
		(stroke
			(width 0)
			(type default)
		)
	)
	(wire
		(pts
			(xy 300.99 224.79) (xy 323.85 224.79)
		)
		(stroke
			(width 0)
			(type default)
		)
	)
	(wire
		(pts
			(xy 62.23 189.23) (xy 62.23 196.85)
		)
		(stroke
			(width 0)
			(type default)
		)
	)
	(wire
		(pts
			(xy 353.06 213.36) (xy 353.06 212.09)
		)
		(stroke
			(width 0)
			(type default)
		)
	)
	(wire
		(pts
			(xy 377.19 212.09) (xy 383.54 212.09)
		)
		(stroke
			(width 0)
			(type default)
		)
	)
	(wire
		(pts
			(xy 224.79 104.14) (xy 229.87 104.14)
		)
		(stroke
			(width 0)
			(type default)
		)
	)
	(wire
		(pts
			(xy 81.28 54.61) (xy 87.63 54.61)
		)
		(stroke
			(width 0)
			(type default)
		)
	)
	(wire
		(pts
			(xy 346.71 175.26) (xy 346.71 173.99)
		)
		(stroke
			(width 0)
			(type default)
		)
	)
	(wire
		(pts
			(xy 236.22 157.48) (xy 236.22 158.75)
		)
		(stroke
			(width 0)
			(type default)
		)
	)
	(wire
		(pts
			(xy 353.06 212.09) (xy 360.68 212.09)
		)
		(stroke
			(width 0)
			(type default)
		)
	)
	(wire
		(pts
			(xy 360.68 40.64) (xy 360.68 41.91)
		)
		(stroke
			(width 0)
			(type default)
		)
	)
	(wire
		(pts
			(xy 123.19 92.71) (xy 120.65 92.71)
		)
		(stroke
			(width 0)
			(type default)
		)
	)
	(wire
		(pts
			(xy 74.93 58.42) (xy 74.93 54.61)
		)
		(stroke
			(width 0)
			(type default)
		)
	)
	(wire
		(pts
			(xy 82.55 201.93) (xy 72.39 201.93)
		)
		(stroke
			(width 0)
			(type default)
		)
	)
	(wire
		(pts
			(xy 88.9 92.71) (xy 95.25 92.71)
		)
		(stroke
			(width 0)
			(type default)
		)
	)
	(wire
		(pts
			(xy 236.22 187.96) (xy 247.65 187.96)
		)
		(stroke
			(width 0)
			(type default)
		)
	)
	(wire
		(pts
			(xy 154.94 81.28) (xy 165.1 81.28)
		)
		(stroke
			(width 0)
			(type default)
		)
	)
	(wire
		(pts
			(xy 252.73 187.96) (xy 260.35 187.96)
		)
		(stroke
			(width 0)
			(type default)
		)
	)
	(wire
		(pts
			(xy 353.06 175.26) (xy 353.06 173.99)
		)
		(stroke
			(width 0)
			(type default)
		)
	)
	(wire
		(pts
			(xy 360.68 130.81) (xy 360.68 129.54)
		)
		(stroke
			(width 0)
			(type default)
		)
	)
	(wire
		(pts
			(xy 353.06 219.71) (xy 360.68 219.71)
		)
		(stroke
			(width 0)
			(type default)
		)
	)
	(wire
		(pts
			(xy 226.06 44.45) (xy 231.14 44.45)
		)
		(stroke
			(width 0)
			(type default)
		)
	)
	(wire
		(pts
			(xy 237.49 124.46) (xy 237.49 125.73)
		)
		(stroke
			(width 0)
			(type default)
		)
	)
	(wire
		(pts
			(xy 252.73 34.29) (xy 260.35 34.29)
		)
		(stroke
			(width 0)
			(type default)
		)
	)
	(wire
		(pts
			(xy 74.93 54.61) (xy 81.28 54.61)
		)
		(stroke
			(width 0)
			(type default)
		)
	)
	(wire
		(pts
			(xy 344.17 222.25) (xy 345.44 222.25)
		)
		(stroke
			(width 0)
			(type default)
		)
	)
	(wire
		(pts
			(xy 322.58 34.29) (xy 323.85 34.29)
		)
		(stroke
			(width 0)
			(type default)
		)
	)
	(wire
		(pts
			(xy 322.58 113.03) (xy 316.23 113.03)
		)
		(stroke
			(width 0)
			(type default)
		)
	)
	(wire
		(pts
			(xy 139.7 83.82) (xy 135.89 83.82)
		)
		(stroke
			(width 0)
			(type default)
		)
	)
	(wire
		(pts
			(xy 226.06 64.77) (xy 226.06 66.04)
		)
		(stroke
			(width 0)
			(type default)
		)
	)
	(wire
		(pts
			(xy 316.23 201.93) (xy 316.23 203.2)
		)
		(stroke
			(width 0)
			(type default)
		)
	)
	(wire
		(pts
			(xy 62.23 182.88) (xy 78.74 182.88)
		)
		(stroke
			(width 0)
			(type default)
		)
	)
	(wire
		(pts
			(xy 345.44 177.8) (xy 345.44 180.34)
		)
		(stroke
			(width 0)
			(type default)
		)
	)
	(wire
		(pts
			(xy 195.58 80.01) (xy 195.58 81.28)
		)
		(stroke
			(width 0)
			(type default)
		)
	)
	(wire
		(pts
			(xy 351.79 123.19) (xy 353.06 123.19)
		)
		(stroke
			(width 0)
			(type default)
		)
	)
	(wire
		(pts
			(xy 346.71 40.64) (xy 344.17 40.64)
		)
		(stroke
			(width 0)
			(type default)
		)
	)
	(wire
		(pts
			(xy 346.71 123.19) (xy 344.17 123.19)
		)
		(stroke
			(width 0)
			(type default)
		)
	)
	(wire
		(pts
			(xy 123.19 92.71) (xy 123.19 100.33)
		)
		(stroke
			(width 0)
			(type default)
		)
	)
	(wire
		(pts
			(xy 344.17 44.45) (xy 345.44 44.45)
		)
		(stroke
			(width 0)
			(type default)
		)
	)
	(wire
		(pts
			(xy 351.79 78.74) (xy 353.06 78.74)
		)
		(stroke
			(width 0)
			(type default)
		)
	)
	(wire
		(pts
			(xy 265.43 93.98) (xy 266.7 93.98)
		)
		(stroke
			(width 0)
			(type default)
		)
	)
	(wire
		(pts
			(xy 322.58 68.58) (xy 316.23 68.58)
		)
		(stroke
			(width 0)
			(type default)
		)
	)
	(wire
		(pts
			(xy 99.06 196.85) (xy 113.03 196.85)
		)
		(stroke
			(width 0)
			(type default)
		)
	)
	(wire
		(pts
			(xy 120.65 199.39) (xy 137.16 199.39)
		)
		(stroke
			(width 0)
			(type default)
		)
	)
	(wire
		(pts
			(xy 369.57 34.29) (xy 377.19 34.29)
		)
		(stroke
			(width 0)
			(type default)
		)
	)
	(wire
		(pts
			(xy 129.54 106.68) (xy 129.54 107.95)
		)
		(stroke
			(width 0)
			(type default)
		)
	)
	(wire
		(pts
			(xy 105.41 189.23) (xy 105.41 194.31)
		)
		(stroke
			(width 0)
			(type default)
		)
	)
	(wire
		(pts
			(xy 54.61 54.61) (xy 64.77 54.61)
		)
		(stroke
			(width 0)
			(type default)
		)
	)
	(wire
		(pts
			(xy 313.69 129.54) (xy 300.99 129.54)
		)
		(stroke
			(width 0)
			(type default)
		)
	)
	(wire
		(pts
			(xy 105.41 182.88) (xy 105.41 184.15)
		)
		(stroke
			(width 0)
			(type default)
		)
	)
	(wire
		(pts
			(xy 300.99 91.44) (xy 323.85 91.44)
		)
		(stroke
			(width 0)
			(type default)
		)
	)
	(wire
		(pts
			(xy 344.17 180.34) (xy 345.44 180.34)
		)
		(stroke
			(width 0)
			(type default)
		)
	)
	(wire
		(pts
			(xy 360.68 123.19) (xy 360.68 124.46)
		)
		(stroke
			(width 0)
			(type default)
		)
	)
	(wire
		(pts
			(xy 345.44 88.9) (xy 345.44 91.44)
		)
		(stroke
			(width 0)
			(type default)
		)
	)
	(wire
		(pts
			(xy 353.06 167.64) (xy 360.68 167.64)
		)
		(stroke
			(width 0)
			(type default)
		)
	)
	(wire
		(pts
			(xy 120.65 189.23) (xy 120.65 199.39)
		)
		(stroke
			(width 0)
			(type default)
		)
	)
	(wire
		(pts
			(xy 393.7 34.29) (xy 396.24 34.29)
		)
		(stroke
			(width 0)
			(type default)
		)
	)
	(wire
		(pts
			(xy 154.94 81.28) (xy 154.94 82.55)
		)
		(stroke
			(width 0)
			(type default)
		)
	)
	(wire
		(pts
			(xy 87.63 54.61) (xy 93.98 54.61)
		)
		(stroke
			(width 0)
			(type default)
		)
	)
	(wire
		(pts
			(xy 345.44 135.89) (xy 345.44 137.16)
		)
		(stroke
			(width 0)
			(type default)
		)
	)
	(wire
		(pts
			(xy 224.79 127) (xy 224.79 128.27)
		)
		(stroke
			(width 0)
			(type default)
		)
	)
	(wire
		(pts
			(xy 165.1 82.55) (xy 165.1 81.28)
		)
		(stroke
			(width 0)
			(type default)
		)
	)
	(wire
		(pts
			(xy 353.06 34.29) (xy 360.68 34.29)
		)
		(stroke
			(width 0)
			(type default)
		)
	)
	(wire
		(pts
			(xy 353.06 86.36) (xy 353.06 85.09)
		)
		(stroke
			(width 0)
			(type default)
		)
	)
	(wire
		(pts
			(xy 322.58 78.74) (xy 322.58 68.58)
		)
		(stroke
			(width 0)
			(type default)
		)
	)
	(wire
		(pts
			(xy 252.73 157.48) (xy 260.35 157.48)
		)
		(stroke
			(width 0)
			(type default)
		)
	)
	(wire
		(pts
			(xy 353.06 175.26) (xy 360.68 175.26)
		)
		(stroke
			(width 0)
			(type default)
		)
	)
	(wire
		(pts
			(xy 226.06 71.12) (xy 226.06 72.39)
		)
		(stroke
			(width 0)
			(type default)
		)
	)
	(wire
		(pts
			(xy 393.7 167.64) (xy 396.24 167.64)
		)
		(stroke
			(width 0)
			(type default)
		)
	)
	(wire
		(pts
			(xy 346.71 86.36) (xy 353.06 86.36)
		)
		(stroke
			(width 0)
			(type default)
		)
	)
	(wire
		(pts
			(xy 120.65 73.66) (xy 129.54 73.66)
		)
		(stroke
			(width 0)
			(type default)
		)
	)
	(wire
		(pts
			(xy 154.94 87.63) (xy 154.94 88.9)
		)
		(stroke
			(width 0)
			(type default)
		)
	)
	(wire
		(pts
			(xy 322.58 123.19) (xy 323.85 123.19)
		)
		(stroke
			(width 0)
			(type default)
		)
	)
	(wire
		(pts
			(xy 360.68 130.81) (xy 360.68 132.08)
		)
		(stroke
			(width 0)
			(type default)
		)
	)
	(wire
		(pts
			(xy 309.88 180.34) (xy 323.85 180.34)
		)
		(stroke
			(width 0)
			(type default)
		)
	)
	(wire
		(pts
			(xy 344.17 212.09) (xy 346.71 212.09)
		)
		(stroke
			(width 0)
			(type default)
		)
	)
	(wire
		(pts
			(xy 353.06 219.71) (xy 353.06 218.44)
		)
		(stroke
			(width 0)
			(type default)
		)
	)
	(wire
		(pts
			(xy 360.68 78.74) (xy 369.57 78.74)
		)
		(stroke
			(width 0)
			(type default)
		)
	)
	(wire
		(pts
			(xy 123.19 105.41) (xy 123.19 106.68)
		)
		(stroke
			(width 0)
			(type default)
		)
	)
	(wire
		(pts
			(xy 360.68 219.71) (xy 360.68 220.98)
		)
		(stroke
			(width 0)
			(type default)
		)
	)
	(wire
		(pts
			(xy 345.44 91.44) (xy 345.44 92.71)
		)
		(stroke
			(width 0)
			(type default)
		)
	)
	(wire
		(pts
			(xy 62.23 196.85) (xy 62.23 203.2)
		)
		(stroke
			(width 0)
			(type default)
		)
	)
	(wire
		(pts
			(xy 135.89 81.28) (xy 135.89 83.82)
		)
		(stroke
			(width 0)
			(type default)
		)
	)
	(wire
		(pts
			(xy 360.68 86.36) (xy 360.68 87.63)
		)
		(stroke
			(width 0)
			(type default)
		)
	)
	(wire
		(pts
			(xy 238.76 62.23) (xy 238.76 63.5)
		)
		(stroke
			(width 0)
			(type default)
		)
	)
	(wire
		(pts
			(xy 265.43 34.29) (xy 266.7 34.29)
		)
		(stroke
			(width 0)
			(type default)
		)
	)
	(wire
		(pts
			(xy 377.19 34.29) (xy 377.19 35.56)
		)
		(stroke
			(width 0)
			(type default)
		)
	)
	(wire
		(pts
			(xy 212.09 104.14) (xy 224.79 104.14)
		)
		(stroke
			(width 0)
			(type default)
		)
	)
	(wire
		(pts
			(xy 154.94 96.52) (xy 154.94 95.25)
		)
		(stroke
			(width 0)
			(type default)
		)
	)
	(wire
		(pts
			(xy 99.06 199.39) (xy 120.65 199.39)
		)
		(stroke
			(width 0)
			(type default)
		)
	)
	(wire
		(pts
			(xy 36.83 62.23) (xy 36.83 63.5)
		)
		(stroke
			(width 0)
			(type default)
		)
	)
	(wire
		(pts
			(xy 95.25 73.66) (xy 93.98 73.66)
		)
		(stroke
			(width 0)
			(type default)
		)
	)
	(wire
		(pts
			(xy 148.59 83.82) (xy 148.59 85.09)
		)
		(stroke
			(width 0)
			(type default)
		)
	)
	(wire
		(pts
			(xy 226.06 72.39) (xy 231.14 72.39)
		)
		(stroke
			(width 0)
			(type default)
		)
	)
	(wire
		(pts
			(xy 64.77 54.61) (xy 64.77 58.42)
		)
		(stroke
			(width 0)
			(type default)
		)
	)
	(wire
		(pts
			(xy 346.71 219.71) (xy 353.06 219.71)
		)
		(stroke
			(width 0)
			(type default)
		)
	)
	(wire
		(pts
			(xy 224.79 96.52) (xy 220.98 96.52)
		)
		(stroke
			(width 0)
			(type default)
		)
	)
	(wire
		(pts
			(xy 99.06 194.31) (xy 105.41 194.31)
		)
		(stroke
			(width 0)
			(type default)
		)
	)
	(wire
		(pts
			(xy 344.17 46.99) (xy 345.44 46.99)
		)
		(stroke
			(width 0)
			(type default)
		)
	)
	(wire
		(pts
			(xy 318.77 218.44) (xy 323.85 218.44)
		)
		(stroke
			(width 0)
			(type default)
		)
	)
	(wire
		(pts
			(xy 265.43 124.46) (xy 266.7 124.46)
		)
		(stroke
			(width 0)
			(type default)
		)
	)
	(wire
		(pts
			(xy 309.88 68.58) (xy 316.23 68.58)
		)
		(stroke
			(width 0)
			(type default)
		)
	)
	(wire
		(pts
			(xy 226.06 36.83) (xy 226.06 38.1)
		)
		(stroke
			(width 0)
			(type default)
		)
	)
	(wire
		(pts
			(xy 71.12 29.21) (xy 71.12 54.61)
		)
		(stroke
			(width 0)
			(type default)
		)
	)
	(wire
		(pts
			(xy 344.17 224.79) (xy 345.44 224.79)
		)
		(stroke
			(width 0)
			(type default)
		)
	)
	(wire
		(pts
			(xy 309.88 24.13) (xy 316.23 24.13)
		)
		(stroke
			(width 0)
			(type default)
		)
	)
	(wire
		(pts
			(xy 360.68 34.29) (xy 369.57 34.29)
		)
		(stroke
			(width 0)
			(type default)
		)
	)
	(polyline
		(pts
			(xy 21.59 198.12) (xy 21.59 214.63)
		)
		(stroke
			(width 0)
			(type dash)
		)
	)
	(wire
		(pts
			(xy 388.62 167.64) (xy 393.7 167.64)
		)
		(stroke
			(width 0)
			(type default)
		)
	)
	(wire
		(pts
			(xy 353.06 41.91) (xy 360.68 41.91)
		)
		(stroke
			(width 0)
			(type default)
		)
	)
	(wire
		(pts
			(xy 39.37 125.73) (xy 39.37 123.19)
		)
		(stroke
			(width 0)
			(type default)
		)
	)
	(wire
		(pts
			(xy 360.68 175.26) (xy 360.68 173.99)
		)
		(stroke
			(width 0)
			(type default)
		)
	)
	(wire
		(pts
			(xy 39.37 128.27) (xy 39.37 129.54)
		)
		(stroke
			(width 0)
			(type default)
		)
	)
	(wire
		(pts
			(xy 309.88 201.93) (xy 316.23 201.93)
		)
		(stroke
			(width 0)
			(type default)
		)
	)
	(wire
		(pts
			(xy 318.77 85.09) (xy 323.85 85.09)
		)
		(stroke
			(width 0)
			(type default)
		)
	)
	(wire
		(pts
			(xy 129.54 105.41) (xy 129.54 106.68)
		)
		(stroke
			(width 0)
			(type default)
		)
	)
	(polyline
		(pts
			(xy 21.59 198.12) (xy 68.58 198.12)
		)
		(stroke
			(width 0)
			(type dash)
		)
	)
	(wire
		(pts
			(xy 223.52 167.64) (xy 228.6 167.64)
		)
		(stroke
			(width 0)
			(type default)
		)
	)
	(wire
		(pts
			(xy 36.83 57.15) (xy 36.83 59.69)
		)
		(stroke
			(width 0)
			(type default)
		)
	)
	(wire
		(pts
			(xy 322.58 34.29) (xy 322.58 24.13)
		)
		(stroke
			(width 0)
			(type default)
		)
	)
	(wire
		(pts
			(xy 226.06 36.83) (xy 220.98 36.83)
		)
		(stroke
			(width 0)
			(type default)
		)
	)
	(wire
		(pts
			(xy 87.63 58.42) (xy 87.63 54.61)
		)
		(stroke
			(width 0)
			(type default)
		)
	)
	(wire
		(pts
			(xy 144.78 83.82) (xy 148.59 83.82)
		)
		(stroke
			(width 0)
			(type default)
		)
	)
	(wire
		(pts
			(xy 238.76 34.29) (xy 247.65 34.29)
		)
		(stroke
			(width 0)
			(type default)
		)
	)
	(wire
		(pts
			(xy 224.79 127) (xy 220.98 127)
		)
		(stroke
			(width 0)
			(type default)
		)
	)
	(wire
		(pts
			(xy 72.39 201.93) (xy 72.39 203.2)
		)
		(stroke
			(width 0)
			(type default)
		)
	)
	(wire
		(pts
			(xy 171.45 81.28) (xy 177.8 81.28)
		)
		(stroke
			(width 0)
			(type default)
		)
	)
	(wire
		(pts
			(xy 353.06 130.81) (xy 360.68 130.81)
		)
		(stroke
			(width 0)
			(type default)
		)
	)
	(wire
		(pts
			(xy 369.57 78.74) (xy 377.19 78.74)
		)
		(stroke
			(width 0)
			(type default)
		)
	)
	(wire
		(pts
			(xy 190.5 81.28) (xy 195.58 81.28)
		)
		(stroke
			(width 0)
			(type default)
		)
	)
	(wire
		(pts
			(xy 80.01 92.71) (xy 80.01 93.98)
		)
		(stroke
			(width 0)
			(type default)
		)
	)
	(wire
		(pts
			(xy 369.57 167.64) (xy 369.57 168.91)
		)
		(stroke
			(width 0)
			(type default)
		)
	)
	(wire
		(pts
			(xy 360.68 175.26) (xy 360.68 176.53)
		)
		(stroke
			(width 0)
			(type default)
		)
	)
	(wire
		(pts
			(xy 62.23 182.88) (xy 62.23 184.15)
		)
		(stroke
			(width 0)
			(type default)
		)
	)
	(wire
		(pts
			(xy 322.58 167.64) (xy 322.58 157.48)
		)
		(stroke
			(width 0)
			(type default)
		)
	)
	(wire
		(pts
			(xy 265.43 62.23) (xy 266.7 62.23)
		)
		(stroke
			(width 0)
			(type default)
		)
	)
	(wire
		(pts
			(xy 80.01 81.28) (xy 80.01 85.09)
		)
		(stroke
			(width 0)
			(type default)
		)
	)
	(wire
		(pts
			(xy 113.03 196.85) (xy 137.16 196.85)
		)
		(stroke
			(width 0)
			(type default)
		)
	)
	(wire
		(pts
			(xy 135.89 95.25) (xy 154.94 95.25)
		)
		(stroke
			(width 0)
			(type default)
		)
	)
	(wire
		(pts
			(xy 129.54 92.71) (xy 129.54 93.98)
		)
		(stroke
			(width 0)
			(type default)
		)
	)
	(wire
		(pts
			(xy 313.69 85.09) (xy 300.99 85.09)
		)
		(stroke
			(width 0)
			(type default)
		)
	)
	(wire
		(pts
			(xy 95.25 81.28) (xy 80.01 81.28)
		)
		(stroke
			(width 0)
			(type default)
		)
	)
	(wire
		(pts
			(xy 165.1 81.28) (xy 171.45 81.28)
		)
		(stroke
			(width 0)
			(type default)
		)
	)
	(wire
		(pts
			(xy 346.71 167.64) (xy 344.17 167.64)
		)
		(stroke
			(width 0)
			(type default)
		)
	)
	(wire
		(pts
			(xy 223.52 160.02) (xy 220.98 160.02)
		)
		(stroke
			(width 0)
			(type default)
		)
	)
	(wire
		(pts
			(xy 78.74 199.39) (xy 78.74 194.31)
		)
		(stroke
			(width 0)
			(type default)
		)
	)
	(wire
		(pts
			(xy 344.17 177.8) (xy 345.44 177.8)
		)
		(stroke
			(width 0)
			(type default)
		)
	)
	(wire
		(pts
			(xy 120.65 182.88) (xy 120.65 184.15)
		)
		(stroke
			(width 0)
			(type default)
		)
	)
	(wire
		(pts
			(xy 316.23 157.48) (xy 316.23 158.75)
		)
		(stroke
			(width 0)
			(type default)
		)
	)
	(wire
		(pts
			(xy 223.52 166.37) (xy 223.52 167.64)
		)
		(stroke
			(width 0)
			(type default)
		)
	)
	(wire
		(pts
			(xy 318.77 173.99) (xy 323.85 173.99)
		)
		(stroke
			(width 0)
			(type default)
		)
	)
	(wire
		(pts
			(xy 309.88 113.03) (xy 316.23 113.03)
		)
		(stroke
			(width 0)
			(type default)
		)
	)
	(wire
		(pts
			(xy 393.7 123.19) (xy 396.24 123.19)
		)
		(stroke
			(width 0)
			(type default)
		)
	)
	(wire
		(pts
			(xy 300.99 173.99) (xy 313.69 173.99)
		)
		(stroke
			(width 0)
			(type default)
		)
	)
	(wire
		(pts
			(xy 224.79 96.52) (xy 224.79 97.79)
		)
		(stroke
			(width 0)
			(type default)
		)
	)
	(wire
		(pts
			(xy 313.69 40.64) (xy 300.99 40.64)
		)
		(stroke
			(width 0)
			(type default)
		)
	)
	(wire
		(pts
			(xy 224.79 133.35) (xy 224.79 134.62)
		)
		(stroke
			(width 0)
			(type default)
		)
	)
	(wire
		(pts
			(xy 353.06 86.36) (xy 360.68 86.36)
		)
		(stroke
			(width 0)
			(type default)
		)
	)
	(wire
		(pts
			(xy 346.71 129.54) (xy 344.17 129.54)
		)
		(stroke
			(width 0)
			(type default)
		)
	)
	(wire
		(pts
			(xy 212.09 44.45) (xy 226.06 44.45)
		)
		(stroke
			(width 0)
			(type default)
		)
	)
	(wire
		(pts
			(xy 120.65 87.63) (xy 135.89 87.63)
		)
		(stroke
			(width 0)
			(type default)
		)
	)
	(wire
		(pts
			(xy 212.09 134.62) (xy 224.79 134.62)
		)
		(stroke
			(width 0)
			(type default)
		)
	)
	(wire
		(pts
			(xy 212.09 198.12) (xy 228.6 198.12)
		)
		(stroke
			(width 0)
			(type default)
		)
	)
	(wire
		(pts
			(xy 171.45 82.55) (xy 171.45 81.28)
		)
		(stroke
			(width 0)
			(type default)
		)
	)
	(wire
		(pts
			(xy 226.06 64.77) (xy 220.98 64.77)
		)
		(stroke
			(width 0)
			(type default)
		)
	)
	(wire
		(pts
			(xy 360.68 123.19) (xy 369.57 123.19)
		)
		(stroke
			(width 0)
			(type default)
		)
	)
	(wire
		(pts
			(xy 346.71 219.71) (xy 346.71 218.44)
		)
		(stroke
			(width 0)
			(type default)
		)
	)
	(wire
		(pts
			(xy 388.62 123.19) (xy 393.7 123.19)
		)
		(stroke
			(width 0)
			(type default)
		)
	)
	(wire
		(pts
			(xy 351.79 167.64) (xy 353.06 167.64)
		)
		(stroke
			(width 0)
			(type default)
		)
	)
	(wire
		(pts
			(xy 353.06 130.81) (xy 353.06 129.54)
		)
		(stroke
			(width 0)
			(type default)
		)
	)
	(wire
		(pts
			(xy 346.71 130.81) (xy 346.71 129.54)
		)
		(stroke
			(width 0)
			(type default)
		)
	)
	(wire
		(pts
			(xy 265.43 157.48) (xy 266.7 157.48)
		)
		(stroke
			(width 0)
			(type default)
		)
	)
	(wire
		(pts
			(xy 120.65 81.28) (xy 121.92 81.28)
		)
		(stroke
			(width 0)
			(type default)
		)
	)
	(wire
		(pts
			(xy 80.01 92.71) (xy 80.01 90.17)
		)
		(stroke
			(width 0)
			(type default)
		)
	)
	(wire
		(pts
			(xy 309.88 157.48) (xy 316.23 157.48)
		)
		(stroke
			(width 0)
			(type default)
		)
	)
	(wire
		(pts
			(xy 129.54 92.71) (xy 123.19 92.71)
		)
		(stroke
			(width 0)
			(type default)
		)
	)
	(wire
		(pts
			(xy 346.71 173.99) (xy 344.17 173.99)
		)
		(stroke
			(width 0)
			(type default)
		)
	)
	(wire
		(pts
			(xy 377.19 167.64) (xy 377.19 168.91)
		)
		(stroke
			(width 0)
			(type default)
		)
	)
	(wire
		(pts
			(xy 38.1 125.73) (xy 39.37 125.73)
		)
		(stroke
			(width 0)
			(type default)
		)
	)
	(wire
		(pts
			(xy 360.68 34.29) (xy 360.68 35.56)
		)
		(stroke
			(width 0)
			(type default)
		)
	)
	(wire
		(pts
			(xy 322.58 201.93) (xy 316.23 201.93)
		)
		(stroke
			(width 0)
			(type default)
		)
	)
	(wire
		(pts
			(xy 377.19 78.74) (xy 377.19 80.01)
		)
		(stroke
			(width 0)
			(type default)
		)
	)
	(wire
		(pts
			(xy 369.57 123.19) (xy 369.57 124.46)
		)
		(stroke
			(width 0)
			(type default)
		)
	)
	(wire
		(pts
			(xy 377.19 167.64) (xy 383.54 167.64)
		)
		(stroke
			(width 0)
			(type default)
		)
	)
	(wire
		(pts
			(xy 135.89 87.63) (xy 135.89 95.25)
		)
		(stroke
			(width 0)
			(type default)
		)
	)
	(wire
		(pts
			(xy 300.99 135.89) (xy 323.85 135.89)
		)
		(stroke
			(width 0)
			(type default)
		)
	)
	(wire
		(pts
			(xy 252.73 93.98) (xy 260.35 93.98)
		)
		(stroke
			(width 0)
			(type default)
		)
	)
	(wire
		(pts
			(xy 144.78 81.28) (xy 154.94 81.28)
		)
		(stroke
			(width 0)
			(type default)
		)
	)
	(wire
		(pts
			(xy 388.62 34.29) (xy 393.7 34.29)
		)
		(stroke
			(width 0)
			(type default)
		)
	)
	(wire
		(pts
			(xy 377.19 123.19) (xy 377.19 124.46)
		)
		(stroke
			(width 0)
			(type default)
		)
	)
	(wire
		(pts
			(xy 252.73 62.23) (xy 260.35 62.23)
		)
		(stroke
			(width 0)
			(type default)
		)
	)
	(wire
		(pts
			(xy 224.79 134.62) (xy 229.87 134.62)
		)
		(stroke
			(width 0)
			(type default)
		)
	)
	(wire
		(pts
			(xy 360.68 43.18) (xy 360.68 41.91)
		)
		(stroke
			(width 0)
			(type default)
		)
	)
	(wire
		(pts
			(xy 377.19 123.19) (xy 383.54 123.19)
		)
		(stroke
			(width 0)
			(type default)
		)
	)
	(wire
		(pts
			(xy 113.03 189.23) (xy 113.03 196.85)
		)
		(stroke
			(width 0)
			(type default)
		)
	)
	(wire
		(pts
			(xy 101.6 201.93) (xy 101.6 203.2)
		)
		(stroke
			(width 0)
			(type default)
		)
	)
	(wire
		(pts
			(xy 238.76 34.29) (xy 238.76 35.56)
		)
		(stroke
			(width 0)
			(type default)
		)
	)
	(wire
		(pts
			(xy 38.1 120.65) (xy 45.72 120.65)
		)
		(stroke
			(width 0)
			(type default)
		)
	)
	(wire
		(pts
			(xy 345.44 133.35) (xy 345.44 135.89)
		)
		(stroke
			(width 0)
			(type default)
		)
	)
	(wire
		(pts
			(xy 318.77 129.54) (xy 323.85 129.54)
		)
		(stroke
			(width 0)
			(type default)
		)
	)
	(wire
		(pts
			(xy 88.9 83.82) (xy 95.25 83.82)
		)
		(stroke
			(width 0)
			(type default)
		)
	)
	(wire
		(pts
			(xy 345.44 180.34) (xy 345.44 181.61)
		)
		(stroke
			(width 0)
			(type default)
		)
	)
	(wire
		(pts
			(xy 88.9 90.17) (xy 88.9 92.71)
		)
		(stroke
			(width 0)
			(type default)
		)
	)
	(wire
		(pts
			(xy 54.61 54.61) (xy 54.61 58.42)
		)
		(stroke
			(width 0)
			(type default)
		)
	)
	(label "5V0_PG"
		(at 212.09 198.12 0)
		(effects
			(font
				(size 1.27 1.27)
			)
			(justify left bottom)
		)
	)
	(label "VCCAUX_EN"
		(at 137.16 196.85 180)
		(effects
			(font
				(size 1.27 1.27)
			)
			(justify right bottom)
		)
	)
	(label "VCCINT_EN"
		(at 300.99 173.99 0)
		(effects
			(font
				(size 1.27 1.27)
			)
			(justify left bottom)
		)
	)
	(label "VCCIO_EN"
		(at 300.99 40.64 0)
		(effects
			(font
				(size 1.27 1.27)
			)
			(justify left bottom)
		)
	)
	(label "VCCIO_EN"
		(at 137.16 199.39 180)
		(effects
			(font
				(size 1.27 1.27)
			)
			(justify right bottom)
		)
	)
	(label "1V2_PG"
		(at 212.09 44.45 0)
		(effects
			(font
				(size 1.27 1.27)
			)
			(justify left bottom)
		)
	)
	(label "VCCIO_EN"
		(at 300.99 218.44 0)
		(effects
			(font
				(size 1.27 1.27)
			)
			(justify left bottom)
		)
	)
	(label "5V0_PG"
		(at 46.99 196.85 0)
		(effects
			(font
				(size 1.27 1.27)
			)
			(justify left bottom)
		)
	)
	(label "5V0_PG"
		(at 120.65 73.66 0)
		(effects
			(font
				(size 1.27 1.27)
			)
			(justify left bottom)
		)
	)
	(label "VCCAUX_EN"
		(at 300.99 85.09 0)
		(effects
			(font
				(size 1.27 1.27)
			)
			(justify left bottom)
		)
	)
	(label "2V5_PG"
		(at 212.09 72.39 0)
		(effects
			(font
				(size 1.27 1.27)
			)
			(justify left bottom)
		)
	)
	(label "1V8_PG"
		(at 300.99 91.44 0)
		(effects
			(font
				(size 1.27 1.27)
			)
			(justify left bottom)
		)
	)
	(label "1V35_PG"
		(at 300.99 135.89 0)
		(effects
			(font
				(size 1.27 1.27)
			)
			(justify left bottom)
		)
	)
	(label "1V35_PG"
		(at 212.09 134.62 0)
		(effects
			(font
				(size 1.27 1.27)
			)
			(justify left bottom)
		)
	)
	(label "VCCINT_EN"
		(at 137.16 194.31 180)
		(effects
			(font
				(size 1.27 1.27)
			)
			(justify right bottom)
		)
	)
	(label "1V2_PG"
		(at 300.99 224.79 0)
		(effects
			(font
				(size 1.27 1.27)
			)
			(justify left bottom)
		)
	)
	(label "VCCIO_EN"
		(at 300.99 129.54 0)
		(effects
			(font
				(size 1.27 1.27)
			)
			(justify left bottom)
		)
	)
	(label "1V8_PG"
		(at 212.09 104.14 0)
		(effects
			(font
				(size 1.27 1.27)
			)
			(justify left bottom)
		)
	)
	(label "VCC12V"
		(at 59.69 29.21 0)
		(effects
			(font
				(size 1.27 1.27)
			)
			(justify left bottom)
		)
	)
	(global_label "3V0_BAT"
		(shape output)
		(at 45.72 120.65 0)
		(fields_autoplaced yes)
		(effects
			(font
				(size 1.27 1.27)
			)
			(justify left)
		)
		(property "Intersheetrefs" "${INTERSHEET_REFS}"
			(at 55.8456 120.5706 0)
			(effects
				(font
					(size 1.27 1.27)
				)
				(justify left)
				(hide yes)
			)
		)
	)
	(global_label "VCC5V0"
		(shape input)
		(at 309.88 201.93 180)
		(fields_autoplaced yes)
		(effects
			(font
				(size 1.27 1.27)
			)
			(justify right)
		)
		(property "Intersheetrefs" "${INTERSHEET_REFS}"
			(at -6.985 177.8 0)
			(effects
				(font
					(size 1.27 1.27)
				)
				(hide yes)
			)
		)
	)
	(global_label "VCC1V35"
		(shape output)
		(at 396.24 123.19 0)
		(fields_autoplaced yes)
		(effects
			(font
				(size 1.27 1.27)
			)
			(justify left)
		)
		(property "Intersheetrefs" "${INTERSHEET_REFS}"
			(at 406.9099 123.1106 0)
			(effects
				(font
					(size 1.27 1.27)
				)
				(justify left)
				(hide yes)
			)
		)
	)
	(global_label "VCC5V0"
		(shape input)
		(at 309.88 157.48 180)
		(fields_autoplaced yes)
		(effects
			(font
				(size 1.27 1.27)
			)
			(justify right)
		)
		(property "Intersheetrefs" "${INTERSHEET_REFS}"
			(at -6.985 133.35 0)
			(effects
				(font
					(size 1.27 1.27)
				)
				(hide yes)
			)
		)
	)
	(global_label "1V0_PG"
		(shape input)
		(at 309.88 180.34 180)
		(fields_autoplaced yes)
		(effects
			(font
				(size 1.27 1.27)
			)
			(justify right)
		)
		(property "Intersheetrefs" "${INTERSHEET_REFS}"
			(at -27.305 -0.635 0)
			(effects
				(font
					(size 1.27 1.27)
				)
				(hide yes)
			)
		)
	)
	(global_label "VCC3V3"
		(shape input)
		(at 266.7 187.96 0)
		(fields_autoplaced yes)
		(effects
			(font
				(size 1.27 1.27)
			)
			(justify left)
		)
		(property "Intersheetrefs" "${INTERSHEET_REFS}"
			(at -16.51 5.715 0)
			(effects
				(font
					(size 1.27 1.27)
				)
				(hide yes)
			)
		)
	)
	(global_label "VCC1V2"
		(shape output)
		(at 396.24 212.09 0)
		(fields_autoplaced yes)
		(effects
			(font
				(size 1.27 1.27)
			)
			(justify left)
		)
		(property "Intersheetrefs" "${INTERSHEET_REFS}"
			(at 405.7004 212.0106 0)
			(effects
				(font
					(size 1.27 1.27)
				)
				(justify left)
				(hide yes)
			)
		)
	)
	(global_label "VCC1V8"
		(shape output)
		(at 396.24 78.74 0)
		(fields_autoplaced yes)
		(effects
			(font
				(size 1.27 1.27)
			)
			(justify left)
		)
		(property "Intersheetrefs" "${INTERSHEET_REFS}"
			(at 405.7004 78.6606 0)
			(effects
				(font
					(size 1.27 1.27)
				)
				(justify left)
				(hide yes)
			)
		)
	)
	(global_label "VCC3V3"
		(shape input)
		(at 266.7 34.29 0)
		(fields_autoplaced yes)
		(effects
			(font
				(size 1.27 1.27)
			)
			(justify left)
		)
		(property "Intersheetrefs" "${INTERSHEET_REFS}"
			(at -18.415 5.08 0)
			(effects
				(font
					(size 1.27 1.27)
				)
				(hide yes)
			)
		)
	)
	(global_label "VCC3V3"
		(shape input)
		(at 220.98 160.02 180)
		(fields_autoplaced yes)
		(effects
			(font
				(size 1.27 1.27)
			)
			(justify right)
		)
		(property "Intersheetrefs" "${INTERSHEET_REFS}"
			(at -22.225 6.985 0)
			(effects
				(font
					(size 1.27 1.27)
				)
				(hide yes)
			)
		)
	)
	(global_label "VCC1V0"
		(shape output)
		(at 396.24 167.64 0)
		(fields_autoplaced yes)
		(effects
			(font
				(size 1.27 1.27)
			)
			(justify left)
		)
		(property "Intersheetrefs" "${INTERSHEET_REFS}"
			(at 405.7004 167.5606 0)
			(effects
				(font
					(size 1.27 1.27)
				)
				(justify left)
				(hide yes)
			)
		)
	)
	(global_label "1V0_PG"
		(shape input)
		(at 220.98 167.64 180)
		(fields_autoplaced yes)
		(effects
			(font
				(size 1.27 1.27)
			)
			(justify right)
		)
		(property "Intersheetrefs" "${INTERSHEET_REFS}"
			(at -22.86 -1.905 0)
			(effects
				(font
					(size 1.27 1.27)
				)
				(hide yes)
			)
		)
	)
	(global_label "VCC5V0"
		(shape input)
		(at 309.88 24.13 180)
		(fields_autoplaced yes)
		(effects
			(font
				(size 1.27 1.27)
			)
			(justify right)
		)
		(property "Intersheetrefs" "${INTERSHEET_REFS}"
			(at -6.985 0 0)
			(effects
				(font
					(size 1.27 1.27)
				)
				(hide yes)
			)
		)
	)
	(global_label "VCC5V0"
		(shape input)
		(at 220.98 96.52 180)
		(fields_autoplaced yes)
		(effects
			(font
				(size 1.27 1.27)
			)
			(justify right)
		)
		(property "Intersheetrefs" "${INTERSHEET_REFS}"
			(at -23.495 6.985 0)
			(effects
				(font
					(size 1.27 1.27)
				)
				(hide yes)
			)
		)
	)
	(global_label "VCC3V3"
		(shape input)
		(at 266.7 124.46 0)
		(fields_autoplaced yes)
		(effects
			(font
				(size 1.27 1.27)
			)
			(justify left)
		)
		(property "Intersheetrefs" "${INTERSHEET_REFS}"
			(at -17.78 5.08 0)
			(effects
				(font
					(size 1.27 1.27)
				)
				(hide yes)
			)
		)
	)
	(global_label "VCC3V3"
		(shape output)
		(at 396.24 34.29 0)
		(fields_autoplaced yes)
		(effects
			(font
				(size 1.27 1.27)
			)
			(justify left)
		)
		(property "Intersheetrefs" "${INTERSHEET_REFS}"
			(at 405.7004 34.2106 0)
			(effects
				(font
					(size 1.27 1.27)
				)
				(justify left)
				(hide yes)
			)
		)
	)
	(global_label "VCC5V0"
		(shape input)
		(at 220.98 36.83 180)
		(fields_autoplaced yes)
		(effects
			(font
				(size 1.27 1.27)
			)
			(justify right)
		)
		(property "Intersheetrefs" "${INTERSHEET_REFS}"
			(at -24.13 6.35 0)
			(effects
				(font
					(size 1.27 1.27)
				)
				(hide yes)
			)
		)
	)
	(global_label "VCC3V3"
		(shape input)
		(at 266.7 157.48 0)
		(fields_autoplaced yes)
		(effects
			(font
				(size 1.27 1.27)
			)
			(justify left)
		)
		(property "Intersheetrefs" "${INTERSHEET_REFS}"
			(at -16.51 5.715 0)
			(effects
				(font
					(size 1.27 1.27)
				)
				(hide yes)
			)
		)
	)
	(global_label "VCC5V0"
		(shape input)
		(at 220.98 64.77 180)
		(fields_autoplaced yes)
		(effects
			(font
				(size 1.27 1.27)
			)
			(justify right)
		)
		(property "Intersheetrefs" "${INTERSHEET_REFS}"
			(at -24.13 6.35 0)
			(effects
				(font
					(size 1.27 1.27)
				)
				(hide yes)
			)
		)
	)
	(global_label "VCC5V0"
		(shape input)
		(at 220.98 127 180)
		(fields_autoplaced yes)
		(effects
			(font
				(size 1.27 1.27)
			)
			(justify right)
		)
		(property "Intersheetrefs" "${INTERSHEET_REFS}"
			(at -23.495 6.35 0)
			(effects
				(font
					(size 1.27 1.27)
				)
				(hide yes)
			)
		)
	)
	(global_label "P12V_AUX"
		(shape input)
		(at 33.02 29.21 180)
		(fields_autoplaced yes)
		(effects
			(font
				(size 1.27 1.27)
			)
			(justify right)
		)
		(property "Intersheetrefs" "${INTERSHEET_REFS}"
			(at -8.255 -27.94 0)
			(effects
				(font
					(size 1.27 1.27)
				)
				(hide yes)
			)
		)
	)
	(global_label "VCC5V0"
		(shape input)
		(at 55.88 182.88 180)
		(fields_autoplaced yes)
		(effects
			(font
				(size 1.27 1.27)
			)
			(justify right)
		)
		(property "Intersheetrefs" "${INTERSHEET_REFS}"
			(at 46.4196 182.9594 0)
			(effects
				(font
					(size 1.27 1.27)
				)
				(justify right)
				(hide yes)
			)
		)
	)
	(global_label "VCC5V0"
		(shape output)
		(at 200.66 81.28 0)
		(fields_autoplaced yes)
		(effects
			(font
				(size 1.27 1.27)
			)
			(justify left)
		)
		(property "Intersheetrefs" "${INTERSHEET_REFS}"
			(at 210.1204 81.2006 0)
			(effects
				(font
					(size 1.27 1.27)
				)
				(justify left)
				(hide yes)
			)
		)
	)
	(global_label "VCC5V0"
		(shape input)
		(at 309.88 68.58 180)
		(fields_autoplaced yes)
		(effects
			(font
				(size 1.27 1.27)
			)
			(justify right)
		)
		(property "Intersheetrefs" "${INTERSHEET_REFS}"
			(at -6.985 44.45 0)
			(effects
				(font
					(size 1.27 1.27)
				)
				(hide yes)
			)
		)
	)
	(global_label "VCC3V3"
		(shape input)
		(at 266.7 93.98 0)
		(fields_autoplaced yes)
		(effects
			(font
				(size 1.27 1.27)
			)
			(justify left)
		)
		(property "Intersheetrefs" "${INTERSHEET_REFS}"
			(at -17.145 5.715 0)
			(effects
				(font
					(size 1.27 1.27)
				)
				(hide yes)
			)
		)
	)
	(global_label "VCC5V0"
		(shape input)
		(at 309.88 113.03 180)
		(fields_autoplaced yes)
		(effects
			(font
				(size 1.27 1.27)
			)
			(justify right)
		)
		(property "Intersheetrefs" "${INTERSHEET_REFS}"
			(at -6.985 88.9 0)
			(effects
				(font
					(size 1.27 1.27)
				)
				(hide yes)
			)
		)
	)
	(global_label "VCC3V3"
		(shape input)
		(at 266.7 62.23 0)
		(fields_autoplaced yes)
		(effects
			(font
				(size 1.27 1.27)
			)
			(justify left)
		)
		(property "Intersheetrefs" "${INTERSHEET_REFS}"
			(at -18.415 5.08 0)
			(effects
				(font
					(size 1.27 1.27)
				)
				(hide yes)
			)
		)
	)
	(symbol
		(lib_id "antmicropower:GND")
		(at 345.44 48.26 0)
		(unit 1)
		(exclude_from_sim no)
		(in_bom yes)
		(on_board yes)
		(dnp no)
		(property "Reference" "#PWR064"
			(at 345.44 54.61 0)
			(effects
				(font
					(size 1.27 1.27)
				)
				(hide yes)
			)
		)
		(property "Value" "GND"
			(at 345.44 52.07 0)
			(effects
				(font
					(size 1.27 1.27)
				)
			)
		)
		(property "Footprint" ""
			(at 345.44 48.26 0)
			(effects
				(font
					(size 1.27 1.27)
				)
				(hide yes)
			)
		)
		(property "Datasheet" ""
			(at 345.44 48.26 0)
			(effects
				(font
					(size 1.27 1.27)
				)
				(hide yes)
			)
		)
		(property "Description" ""
			(at 345.44 48.26 0)
			(effects
				(font
					(size 1.27 1.27)
				)
				(hide yes)
			)
		)
		(property "Author" "Antmicro"
			(at 354.33 55.88 0)
			(effects
				(font
					(size 1.27 1.27)
					(thickness 0.15)
				)
				(justify left bottom)
				(hide yes)
			)
		)
		(property "License" "Apache-2.0"
			(at 354.33 58.42 0)
			(effects
				(font
					(size 1.27 1.27)
					(thickness 0.15)
				)
				(justify left bottom)
				(hide yes)
			)
		)
		(pin "1"
		)
		(instances
			(project "artix-dc-scm"
				(path ""
					(reference "#PWR064")
					(unit 1)
				)
			)
		)
	)
	(symbol
		(lib_id "antmicroResistorsmisc:R_0R_1206")
		(at 190.5 81.28 180)
		(unit 1)
		(exclude_from_sim no)
		(in_bom yes)
		(on_board yes)
		(dnp no)
		(property "Reference" "R69"
			(at 187.96 78.74 0)
			(effects
				(font
					(size 1.27 1.27)
				)
			)
		)
		(property "Value" "R_0R_1206"
			(at 170.18 68.58 0)
			(effects
				(font
					(size 1.27 1.27)
					(thickness 0.15)
				)
				(justify left bottom)
				(hide yes)
			)
		)
		(property "Footprint" "antmicro-footprints:R_1206_3216Metric"
			(at 170.18 66.04 0)
			(effects
				(font
					(size 1.27 1.27)
					(thickness 0.15)
				)
				(justify left bottom)
				(hide yes)
			)
		)
		(property "Datasheet" "https://www.farnell.com/datasheets/2860635.pdf"
			(at 170.18 63.5 0)
			(effects
				(font
					(size 1.27 1.27)
					(thickness 0.15)
				)
				(justify left bottom)
				(hide yes)
			)
		)
		(property "Description" "Zero Ohm Resistor, Jumper, 1206 [3216 Metric], Thick Film, 250 mW, 2 A, Surface Mount Device"
			(at 190.5 81.28 0)
			(effects
				(font
					(size 1.27 1.27)
				)
				(hide yes)
			)
		)
		(property "Manufacturer" "Multicomp Pro"
			(at 170.18 58.42 0)
			(effects
				(font
					(size 1.27 1.27)
					(thickness 0.15)
				)
				(justify left bottom)
				(hide yes)
			)
		)
		(property "MPN" "MCMR12X000_PTL"
			(at 170.18 60.96 0)
			(effects
				(font
					(size 1.27 1.27)
					(thickness 0.15)
				)
				(justify left bottom)
				(hide yes)
			)
		)
		(property "Val" "0R"
			(at 187.96 83.82 0)
			(effects
				(font
					(size 1.27 1.27)
					(thickness 0.15)
				)
			)
		)
		(property "License" "Apache-2.0"
			(at 170.18 55.88 0)
			(effects
				(font
					(size 1.27 1.27)
					(thickness 0.15)
				)
				(justify left bottom)
				(hide yes)
			)
		)
		(property "Author" "Antmicro"
			(at 170.18 53.34 0)
			(effects
				(font
					(size 1.27 1.27)
					(thickness 0.15)
				)
				(justify left bottom)
				(hide yes)
			)
		)
		(property "Tolerance" "~"
			(at 170.18 71.12 0)
			(effects
				(font
					(size 1.27 1.27)
				)
				(justify left bottom)
				(hide yes)
			)
		)
		(property "Current" "2A"
			(at 187.96 77.47 0)
			(effects
				(font
					(size 1.27 1.27)
					(thickness 0.15)
				)
				(hide yes)
			)
		)
		(pin "1"
		)
		(pin "2"
		)
		(instances
			(project "artix-dc-scm"
				(path ""
					(reference "R69")
					(unit 1)
				)
			)
		)
	)
	(symbol
		(lib_id "antmicroFuses:F_3A_1206")
		(at 44.45 29.21 0)
		(unit 1)
		(exclude_from_sim no)
		(in_bom yes)
		(on_board yes)
		(dnp no)
		(property "Reference" "F1"
			(at 46.99 27.305 0)
			(effects
				(font
					(size 1.27 1.27)
				)
			)
		)
		(property "Value" "F_3A_1206"
			(at 46.99 31.115 0)
			(effects
				(font
					(size 1.27 1.27)
				)
				(hide yes)
			)
		)
		(property "Footprint" "antmicro-footprints:F_1206_3216Metric"
			(at 64.77 39.37 0)
			(effects
				(font
					(size 1.27 1.27)
					(thickness 0.15)
				)
				(justify left bottom)
				(hide yes)
			)
		)
		(property "Datasheet" "https://www.littelfuse.com/~/media/electronics/datasheets/fuses/littelfuse_fuse_466_datasheet.pdf.pdf"
			(at 64.77 41.91 0)
			(effects
				(font
					(size 1.27 1.27)
					(thickness 0.15)
				)
				(justify left bottom)
				(hide yes)
			)
		)
		(property "Description" "Fuse, Surface Mount, 3 A, Very Fast Acting, 32 V, 32 V, 1206 (3216 Metric), 466"
			(at 44.45 29.21 0)
			(effects
				(font
					(size 1.27 1.27)
				)
				(hide yes)
			)
		)
		(property "Manufacturer" "Littelfuse"
			(at 64.77 44.45 0)
			(effects
				(font
					(size 1.27 1.27)
					(thickness 0.15)
				)
				(justify left bottom)
				(hide yes)
			)
		)
		(property "MPN" "0466003.NR "
			(at 46.99 31.115 0)
			(effects
				(font
					(size 1.27 1.27)
					(thickness 0.15)
				)
			)
		)
		(property "Author" "Antmicro"
			(at 64.77 49.53 0)
			(effects
				(font
					(size 1.27 1.27)
					(thickness 0.15)
				)
				(justify left bottom)
				(hide yes)
			)
		)
		(property "License" "Apache-2.0"
			(at 64.77 52.07 0)
			(effects
				(font
					(size 1.27 1.27)
					(thickness 0.15)
				)
				(justify left bottom)
				(hide yes)
			)
		)
		(pin "1"
		)
		(pin "2"
		)
		(instances
			(project "artix-dc-scm"
				(path ""
					(reference "F1")
					(unit 1)
				)
			)
		)
	)
	(symbol
		(lib_id "antmicropower:GND")
		(at 36.83 63.5 0)
		(unit 1)
		(exclude_from_sim no)
		(in_bom yes)
		(on_board yes)
		(dnp no)
		(property "Reference" "#PWR0109"
			(at 36.83 69.85 0)
			(effects
				(font
					(size 1.27 1.27)
				)
				(hide yes)
			)
		)
		(property "Value" "GND"
			(at 36.83 67.31 0)
			(effects
				(font
					(size 1.27 1.27)
				)
			)
		)
		(property "Footprint" ""
			(at 36.83 63.5 0)
			(effects
				(font
					(size 1.27 1.27)
				)
				(hide yes)
			)
		)
		(property "Datasheet" ""
			(at 36.83 63.5 0)
			(effects
				(font
					(size 1.27 1.27)
				)
				(hide yes)
			)
		)
		(property "Description" ""
			(at 36.83 63.5 0)
			(effects
				(font
					(size 1.27 1.27)
				)
				(hide yes)
			)
		)
		(property "Author" "Antmicro"
			(at 45.72 71.12 0)
			(effects
				(font
					(size 1.27 1.27)
					(thickness 0.15)
				)
				(justify left bottom)
				(hide yes)
			)
		)
		(property "License" "Apache-2.0"
			(at 45.72 73.66 0)
			(effects
				(font
					(size 1.27 1.27)
					(thickness 0.15)
				)
				(justify left bottom)
				(hide yes)
			)
		)
		(pin "1"
		)
		(instances
			(project "artix-dc-scm"
				(path ""
					(reference "#PWR0109")
					(unit 1)
				)
			)
		)
	)
	(symbol
		(lib_id "antmicropower:GND")
		(at 39.37 129.54 0)
		(unit 1)
		(exclude_from_sim no)
		(in_bom yes)
		(on_board yes)
		(dnp no)
		(property "Reference" "#PWR059"
			(at 39.37 135.89 0)
			(effects
				(font
					(size 1.27 1.27)
				)
				(hide yes)
			)
		)
		(property "Value" "GND"
			(at 39.37 133.35 0)
			(effects
				(font
					(size 1.27 1.27)
				)
			)
		)
		(property "Footprint" ""
			(at 39.37 129.54 0)
			(effects
				(font
					(size 1.27 1.27)
				)
				(hide yes)
			)
		)
		(property "Datasheet" ""
			(at 39.37 129.54 0)
			(effects
				(font
					(size 1.27 1.27)
				)
				(hide yes)
			)
		)
		(property "Description" ""
			(at 39.37 129.54 0)
			(effects
				(font
					(size 1.27 1.27)
				)
				(hide yes)
			)
		)
		(property "Author" "Antmicro"
			(at 48.26 137.16 0)
			(effects
				(font
					(size 1.27 1.27)
					(thickness 0.15)
				)
				(justify left bottom)
				(hide yes)
			)
		)
		(property "License" "Apache-2.0"
			(at 48.26 139.7 0)
			(effects
				(font
					(size 1.27 1.27)
					(thickness 0.15)
				)
				(justify left bottom)
				(hide yes)
			)
		)
		(pin "1"
		)
		(instances
			(project "artix-dc-scm"
				(path ""
					(reference "#PWR059")
					(unit 1)
				)
			)
		)
	)
	(symbol
		(lib_id "antmicroResistors0402:R_0R_0402")
		(at 318.77 40.64 180)
		(unit 1)
		(exclude_from_sim no)
		(in_bom yes)
		(on_board yes)
		(dnp no)
		(property "Reference" "R14"
			(at 316.23 38.1 0)
			(effects
				(font
					(size 1.27 1.27)
				)
			)
		)
		(property "Value" "R_0R_0402"
			(at 298.45 27.94 0)
			(effects
				(font
					(size 1.27 1.27)
					(thickness 0.15)
				)
				(justify left bottom)
				(hide yes)
			)
		)
		(property "Footprint" "antmicro-footprints:R_0402_1005Metric"
			(at 298.45 25.4 0)
			(effects
				(font
					(size 1.27 1.27)
					(thickness 0.15)
				)
				(justify left bottom)
				(hide yes)
			)
		)
		(property "Datasheet" "https://industrial.panasonic.com/cdbs/www-data/pdf/RDA0000/AOA0000C301.pdf"
			(at 298.45 22.86 0)
			(effects
				(font
					(size 1.27 1.27)
					(thickness 0.15)
				)
				(justify left bottom)
				(hide yes)
			)
		)
		(property "Description" "SMD Chip Resistor, Jumper, 0 ohm, 100 mW, 0402 [1005 Metric], Thick Film, General Purpose"
			(at 318.77 40.64 0)
			(effects
				(font
					(size 1.27 1.27)
				)
				(hide yes)
			)
		)
		(property "Manufacturer" "Panasonic"
			(at 298.45 17.78 0)
			(effects
				(font
					(size 1.27 1.27)
					(thickness 0.15)
				)
				(justify left bottom)
				(hide yes)
			)
		)
		(property "MPN" "ERJ2GE0R00X"
			(at 298.45 20.32 0)
			(effects
				(font
					(size 1.27 1.27)
					(thickness 0.15)
				)
				(justify left bottom)
				(hide yes)
			)
		)
		(property "Val" "0R"
			(at 316.23 43.18 0)
			(effects
				(font
					(size 1.27 1.27)
					(thickness 0.15)
				)
			)
		)
		(property "License" "Apache-2.0"
			(at 298.45 15.24 0)
			(effects
				(font
					(size 1.27 1.27)
					(thickness 0.15)
				)
				(justify left bottom)
				(hide yes)
			)
		)
		(property "Author" "Antmicro"
			(at 298.45 12.7 0)
			(effects
				(font
					(size 1.27 1.27)
					(thickness 0.15)
				)
				(justify left bottom)
				(hide yes)
			)
		)
		(property "Tolerance" "~"
			(at 298.45 30.48 0)
			(effects
				(font
					(size 1.27 1.27)
				)
				(justify left bottom)
				(hide yes)
			)
		)
		(property "Current" "1A"
			(at 316.23 49.53 0)
			(effects
				(font
					(size 1.27 1.27)
					(thickness 0.15)
				)
				(hide yes)
			)
		)
		(pin "1"
		)
		(pin "2"
		)
		(instances
			(project "artix-dc-scm"
				(path ""
					(reference "R14")
					(unit 1)
				)
			)
		)
	)
	(symbol
		(lib_id "antmicroResistors0402:R_0R_0402")
		(at 318.77 85.09 180)
		(unit 1)
		(exclude_from_sim no)
		(in_bom yes)
		(on_board yes)
		(dnp no)
		(property "Reference" "R15"
			(at 316.23 82.55 0)
			(effects
				(font
					(size 1.27 1.27)
				)
			)
		)
		(property "Value" "R_0R_0402"
			(at 298.45 72.39 0)
			(effects
				(font
					(size 1.27 1.27)
					(thickness 0.15)
				)
				(justify left bottom)
				(hide yes)
			)
		)
		(property "Footprint" "antmicro-footprints:R_0402_1005Metric"
			(at 298.45 69.85 0)
			(effects
				(font
					(size 1.27 1.27)
					(thickness 0.15)
				)
				(justify left bottom)
				(hide yes)
			)
		)
		(property "Datasheet" "https://industrial.panasonic.com/cdbs/www-data/pdf/RDA0000/AOA0000C301.pdf"
			(at 298.45 67.31 0)
			(effects
				(font
					(size 1.27 1.27)
					(thickness 0.15)
				)
				(justify left bottom)
				(hide yes)
			)
		)
		(property "Description" "SMD Chip Resistor, Jumper, 0 ohm, 100 mW, 0402 [1005 Metric], Thick Film, General Purpose"
			(at 318.77 85.09 0)
			(effects
				(font
					(size 1.27 1.27)
				)
				(hide yes)
			)
		)
		(property "Manufacturer" "Panasonic"
			(at 298.45 62.23 0)
			(effects
				(font
					(size 1.27 1.27)
					(thickness 0.15)
				)
				(justify left bottom)
				(hide yes)
			)
		)
		(property "MPN" "ERJ2GE0R00X"
			(at 298.45 64.77 0)
			(effects
				(font
					(size 1.27 1.27)
					(thickness 0.15)
				)
				(justify left bottom)
				(hide yes)
			)
		)
		(property "Val" "0R"
			(at 316.23 87.63 0)
			(effects
				(font
					(size 1.27 1.27)
					(thickness 0.15)
				)
			)
		)
		(property "License" "Apache-2.0"
			(at 298.45 59.69 0)
			(effects
				(font
					(size 1.27 1.27)
					(thickness 0.15)
				)
				(justify left bottom)
				(hide yes)
			)
		)
		(property "Author" "Antmicro"
			(at 298.45 57.15 0)
			(effects
				(font
					(size 1.27 1.27)
					(thickness 0.15)
				)
				(justify left bottom)
				(hide yes)
			)
		)
		(property "Tolerance" "~"
			(at 298.45 74.93 0)
			(effects
				(font
					(size 1.27 1.27)
				)
				(justify left bottom)
				(hide yes)
			)
		)
		(property "Current" "1A"
			(at 316.23 93.345 0)
			(effects
				(font
					(size 1.27 1.27)
					(thickness 0.15)
				)
				(hide yes)
			)
		)
		(pin "1"
		)
		(pin "2"
		)
		(instances
			(project "artix-dc-scm"
				(path ""
					(reference "R15")
					(unit 1)
				)
			)
		)
	)
	(symbol
		(lib_id "antmicroCapacitors0603:C_10u_0603")
		(at 316.23 208.28 90)
		(unit 1)
		(exclude_from_sim no)
		(in_bom yes)
		(on_board yes)
		(dnp no)
		(property "Reference" "C2"
			(at 316.865 203.835 90)
			(effects
				(font
					(size 1.27 1.27)
				)
				(justify right)
			)
		)
		(property "Value" "C_10u_0603"
			(at 326.39 187.96 0)
			(effects
				(font
					(size 1.27 1.27)
					(thickness 0.15)
				)
				(justify left bottom)
				(hide yes)
			)
		)
		(property "Footprint" "antmicro-footprints:C_0603_1608Metric"
			(at 328.93 187.96 0)
			(effects
				(font
					(size 1.27 1.27)
					(thickness 0.15)
				)
				(justify left bottom)
				(hide yes)
			)
		)
		(property "Datasheet" "https://www.murata.com/products/productdetail?partno=GRM188R61A106KE69%23"
			(at 331.47 187.96 0)
			(effects
				(font
					(size 1.27 1.27)
					(thickness 0.15)
				)
				(justify left bottom)
				(hide yes)
			)
		)
		(property "Description" "SMD Multilayer Ceramic Capacitor, 10 µF, 10 V, 0603 [1608 Metric], ± 10%, X5R, GRM Series"
			(at 316.23 208.28 0)
			(effects
				(font
					(size 1.27 1.27)
				)
				(hide yes)
			)
		)
		(property "Manufacturer" "Murata"
			(at 336.55 187.96 0)
			(effects
				(font
					(size 1.27 1.27)
					(thickness 0.15)
				)
				(justify left bottom)
				(hide yes)
			)
		)
		(property "MPN" "GRM188R61A106KE69D"
			(at 334.01 187.96 0)
			(effects
				(font
					(size 1.27 1.27)
					(thickness 0.15)
				)
				(justify left bottom)
				(hide yes)
			)
		)
		(property "Val" "10u"
			(at 316.865 207.645 90)
			(effects
				(font
					(size 1.27 1.27)
					(thickness 0.15)
				)
				(justify right)
			)
		)
		(property "License" "Apache-2.0"
			(at 339.09 187.96 0)
			(effects
				(font
					(size 1.27 1.27)
					(thickness 0.15)
				)
				(justify left bottom)
				(hide yes)
			)
		)
		(property "Author" "Antmicro"
			(at 341.63 187.96 0)
			(effects
				(font
					(size 1.27 1.27)
					(thickness 0.15)
				)
				(justify left bottom)
				(hide yes)
			)
		)
		(property "Voltage" ""
			(at 344.17 187.96 0)
			(effects
				(font
					(size 1.27 1.27)
				)
				(justify left bottom)
				(hide yes)
			)
		)
		(property "Dielectric" "template_dielectric"
			(at 346.71 187.96 0)
			(effects
				(font
					(size 1.27 1.27)
				)
				(justify left bottom)
				(hide yes)
			)
		)
		(pin "1"
		)
		(pin "2"
		)
		(instances
			(project "artix-dc-scm"
				(path ""
					(reference "C2")
					(unit 1)
				)
			)
		)
	)
	(symbol
		(lib_id "antmicroDCDCConverters:TPS62823DLCT")
		(at 323.85 212.09 0)
		(unit 1)
		(exclude_from_sim no)
		(in_bom yes)
		(on_board yes)
		(dnp no)
		(property "Reference" "U16"
			(at 334.01 205.74 0)
			(effects
				(font
					(size 1.27 1.27)
				)
			)
		)
		(property "Value" "TPS62823DLCT"
			(at 334.01 208.28 0)
			(effects
				(font
					(size 1.27 1.27)
				)
			)
		)
		(property "Footprint" "antmicro-footprints:QFN-8_2x1.5mm"
			(at 358.14 215.9 0)
			(effects
				(font
					(size 1.27 1.27)
					(thickness 0.15)
				)
				(justify left bottom)
				(hide yes)
			)
		)
		(property "Datasheet" "https://www.ti.com/lit/ds/symlink/tps62823.pdf?ts=1685970309606&ref_url=https%253A%252F%252Fwww.ti.com%252Fproduct%252FTPS62823%252Fpart-details%252FTPS62823DLCT"
			(at 358.14 218.44 0)
			(effects
				(font
					(size 1.27 1.27)
					(thickness 0.15)
				)
				(justify left bottom)
				(hide yes)
			)
		)
		(property "Description" "DC/DC converter"
			(at 323.85 212.09 0)
			(effects
				(font
					(size 1.27 1.27)
				)
				(hide yes)
			)
		)
		(property "MPN" "TPS62823DLCT"
			(at 358.14 220.98 0)
			(effects
				(font
					(size 1.27 1.27)
					(thickness 0.15)
				)
				(justify left bottom)
				(hide yes)
			)
		)
		(property "Manufacturer" "Texas Instruments"
			(at 358.14 223.52 0)
			(effects
				(font
					(size 1.27 1.27)
					(thickness 0.15)
				)
				(justify left bottom)
				(hide yes)
			)
		)
		(property "Author" "Antmicro"
			(at 358.14 226.06 0)
			(effects
				(font
					(size 1.27 1.27)
					(thickness 0.15)
				)
				(justify left bottom)
				(hide yes)
			)
		)
		(property "License" "Apache-2.0"
			(at 358.14 228.6 0)
			(effects
				(font
					(size 1.27 1.27)
					(thickness 0.15)
				)
				(justify left bottom)
				(hide yes)
			)
		)
		(pin "4"
		)
		(pin "1"
		)
		(pin "2"
		)
		(pin "3"
		)
		(pin "5"
		)
		(pin "6"
		)
		(pin "7"
		)
		(pin "8"
		)
		(instances
			(project "artix-dc-scm"
				(path ""
					(reference "U16")
					(unit 1)
				)
			)
		)
	)
	(symbol
		(lib_id "antmicroCapacitors0402:C_120p_100V_0402")
		(at 353.06 218.44 90)
		(unit 1)
		(exclude_from_sim no)
		(in_bom yes)
		(on_board yes)
		(dnp no)
		(property "Reference" "C3"
			(at 353.695 213.995 90)
			(effects
				(font
					(size 1.27 1.27)
				)
				(justify right)
			)
		)
		(property "Value" "C_120p_0402"
			(at 363.22 198.12 0)
			(effects
				(font
					(size 1.27 1.27)
					(thickness 0.15)
				)
				(justify left bottom)
				(hide yes)
			)
		)
		(property "Footprint" "antmicro-footprints:C_0402_1005Metric"
			(at 365.76 198.12 0)
			(effects
				(font
					(size 1.27 1.27)
					(thickness 0.15)
				)
				(justify left bottom)
				(hide yes)
			)
		)
		(property "Datasheet" "https://www.kemet.com/en/us/capacitors/product/C0402C121J5GACTU.html"
			(at 368.3 198.12 0)
			(effects
				(font
					(size 1.27 1.27)
					(thickness 0.15)
				)
				(justify left bottom)
				(hide yes)
			)
		)
		(property "Description" "120 pF ±2% 100V Ceramic Capacitor C0G, NP0 0402 (1005 Metric)"
			(at 353.06 218.44 0)
			(effects
				(font
					(size 1.27 1.27)
				)
				(hide yes)
			)
		)
		(property "Manufacturer" "KEMET"
			(at 373.38 198.12 0)
			(effects
				(font
					(size 1.27 1.27)
					(thickness 0.15)
				)
				(justify left bottom)
				(hide yes)
			)
		)
		(property "MPN" "C0402C121J5GACTU"
			(at 370.84 198.12 0)
			(effects
				(font
					(size 1.27 1.27)
					(thickness 0.15)
				)
				(justify left bottom)
				(hide yes)
			)
		)
		(property "Val" "120p"
			(at 353.695 217.805 90)
			(effects
				(font
					(size 1.27 1.27)
					(thickness 0.15)
				)
				(justify right)
			)
		)
		(property "License" "Apache-2.0"
			(at 375.92 198.12 0)
			(effects
				(font
					(size 1.27 1.27)
					(thickness 0.15)
				)
				(justify left bottom)
				(hide yes)
			)
		)
		(property "Author" "Antmicro"
			(at 378.46 198.12 0)
			(effects
				(font
					(size 1.27 1.27)
					(thickness 0.15)
				)
				(justify left bottom)
				(hide yes)
			)
		)
		(property "Voltage" "100V"
			(at 381 198.12 0)
			(effects
				(font
					(size 1.27 1.27)
				)
				(justify left bottom)
				(hide yes)
			)
		)
		(property "Dielectric" "C0G"
			(at 383.54 198.12 0)
			(effects
				(font
					(size 1.27 1.27)
				)
				(justify left bottom)
				(hide yes)
			)
		)
		(pin "1"
		)
		(pin "2"
		)
		(instances
			(project "artix-dc-scm"
				(path ""
					(reference "C3")
					(unit 1)
				)
			)
		)
	)
	(symbol
		(lib_id "antmicroResistors0402:R_100k_0402")
		(at 360.68 220.98 270)
		(unit 1)
		(exclude_from_sim no)
		(in_bom yes)
		(on_board yes)
		(dnp no)
		(property "Reference" "R187"
			(at 361.95 222.25 90)
			(effects
				(font
					(size 1.27 1.27)
				)
				(justify left)
			)
		)
		(property "Value" "R_100k_0402"
			(at 347.98 241.3 0)
			(effects
				(font
					(size 1.27 1.27)
					(thickness 0.15)
				)
				(justify left bottom)
				(hide yes)
			)
		)
		(property "Footprint" "antmicro-footprints:R_0402_1005Metric"
			(at 345.44 241.3 0)
			(effects
				(font
					(size 1.27 1.27)
					(thickness 0.15)
				)
				(justify left bottom)
				(hide yes)
			)
		)
		(property "Datasheet" "https://www.bourns.com/docs/product-datasheets/cr.pdf"
			(at 342.9 241.3 0)
			(effects
				(font
					(size 1.27 1.27)
					(thickness 0.15)
				)
				(justify left bottom)
				(hide yes)
			)
		)
		(property "Description" "SMD Chip Resistor, 100 kohm, ± 1%, 62.5 mW, 0402 [1005 Metric], Thick Film, General Purpose"
			(at 360.68 220.98 0)
			(effects
				(font
					(size 1.27 1.27)
				)
				(hide yes)
			)
		)
		(property "Manufacturer" "Bourns"
			(at 337.82 241.3 0)
			(effects
				(font
					(size 1.27 1.27)
					(thickness 0.15)
				)
				(justify left bottom)
				(hide yes)
			)
		)
		(property "MPN" "CR0402-FX-1003GLF"
			(at 340.36 241.3 0)
			(effects
				(font
					(size 1.27 1.27)
					(thickness 0.15)
				)
				(justify left bottom)
				(hide yes)
			)
		)
		(property "Val" "100k"
			(at 361.95 224.79 90)
			(effects
				(font
					(size 1.27 1.27)
					(thickness 0.15)
				)
				(justify left)
			)
		)
		(property "License" "Apache-2.0"
			(at 335.28 241.3 0)
			(effects
				(font
					(size 1.27 1.27)
					(thickness 0.15)
				)
				(justify left bottom)
				(hide yes)
			)
		)
		(property "Author" "Antmicro"
			(at 332.74 241.3 0)
			(effects
				(font
					(size 1.27 1.27)
					(thickness 0.15)
				)
				(justify left bottom)
				(hide yes)
			)
		)
		(property "Tolerance" "1%"
			(at 350.52 241.3 0)
			(effects
				(font
					(size 1.27 1.27)
				)
				(justify left bottom)
				(hide yes)
			)
		)
		(pin "1"
		)
		(pin "2"
		)
		(instances
			(project "artix-dc-scm"
				(path ""
					(reference "R187")
					(unit 1)
				)
			)
		)
	)
	(symbol
		(lib_id "antmicroCapacitors0402:C_10u_0402")
		(at 369.57 218.44 90)
		(unit 1)
		(exclude_from_sim no)
		(in_bom yes)
		(on_board yes)
		(dnp no)
		(property "Reference" "C101"
			(at 370.205 213.995 90)
			(effects
				(font
					(size 1.27 1.27)
				)
				(justify right)
			)
		)
		(property "Value" "C_10u_0402"
			(at 379.73 198.12 0)
			(effects
				(font
					(size 1.27 1.27)
					(thickness 0.15)
				)
				(justify left bottom)
				(hide yes)
			)
		)
		(property "Footprint" "antmicro-footprints:C_0402_1005Metric"
			(at 382.27 198.12 0)
			(effects
				(font
					(size 1.27 1.27)
					(thickness 0.15)
				)
				(justify left bottom)
				(hide yes)
			)
		)
		(property "Datasheet" "https://www.yageo.com/en/Chart/Download/pdf/CC0402MRX5R5BB106"
			(at 384.81 198.12 0)
			(effects
				(font
					(size 1.27 1.27)
					(thickness 0.15)
				)
				(justify left bottom)
				(hide yes)
			)
		)
		(property "Description" "SMD Multilayer Ceramic Capacitor, 10 µF, 6.3 V, 0402 [1005 Metric], ± 20%, X5R, CC Series"
			(at 369.57 218.44 0)
			(effects
				(font
					(size 1.27 1.27)
				)
				(hide yes)
			)
		)
		(property "Manufacturer" "YAGEO"
			(at 389.89 198.12 0)
			(effects
				(font
					(size 1.27 1.27)
					(thickness 0.15)
				)
				(justify left bottom)
				(hide yes)
			)
		)
		(property "MPN" "CC0402MRX5R5BB106"
			(at 387.35 198.12 0)
			(effects
				(font
					(size 1.27 1.27)
					(thickness 0.15)
				)
				(justify left bottom)
				(hide yes)
			)
		)
		(property "Val" "10u"
			(at 370.205 217.805 90)
			(effects
				(font
					(size 1.27 1.27)
					(thickness 0.15)
				)
				(justify right)
			)
		)
		(property "License" "Apache-2.0"
			(at 392.43 198.12 0)
			(effects
				(font
					(size 1.27 1.27)
					(thickness 0.15)
				)
				(justify left bottom)
				(hide yes)
			)
		)
		(property "Author" "Antmicro"
			(at 394.97 198.12 0)
			(effects
				(font
					(size 1.27 1.27)
					(thickness 0.15)
				)
				(justify left bottom)
				(hide yes)
			)
		)
		(property "Voltage" ""
			(at 397.51 198.12 0)
			(effects
				(font
					(size 1.27 1.27)
				)
				(justify left bottom)
				(hide yes)
			)
		)
		(property "Dielectric" ""
			(at 400.05 198.12 0)
			(effects
				(font
					(size 1.27 1.27)
				)
				(justify left bottom)
				(hide yes)
			)
		)
		(pin "1"
		)
		(pin "2"
		)
		(instances
			(project "artix-dc-scm"
				(path ""
					(reference "C101")
					(unit 1)
				)
			)
		)
	)
	(symbol
		(lib_id "antmicroCapacitors0402:C_10u_0402")
		(at 377.19 218.44 90)
		(unit 1)
		(exclude_from_sim no)
		(in_bom yes)
		(on_board yes)
		(dnp no)
		(property "Reference" "C103"
			(at 377.825 213.995 90)
			(effects
				(font
					(size 1.27 1.27)
				)
				(justify right)
			)
		)
		(property "Value" "C_10u_0402"
			(at 387.35 198.12 0)
			(effects
				(font
					(size 1.27 1.27)
					(thickness 0.15)
				)
				(justify left bottom)
				(hide yes)
			)
		)
		(property "Footprint" "antmicro-footprints:C_0402_1005Metric"
			(at 389.89 198.12 0)
			(effects
				(font
					(size 1.27 1.27)
					(thickness 0.15)
				)
				(justify left bottom)
				(hide yes)
			)
		)
		(property "Datasheet" "https://www.yageo.com/en/Chart/Download/pdf/CC0402MRX5R5BB106"
			(at 392.43 198.12 0)
			(effects
				(font
					(size 1.27 1.27)
					(thickness 0.15)
				)
				(justify left bottom)
				(hide yes)
			)
		)
		(property "Description" "SMD Multilayer Ceramic Capacitor, 10 µF, 6.3 V, 0402 [1005 Metric], ± 20%, X5R, CC Series"
			(at 377.19 218.44 0)
			(effects
				(font
					(size 1.27 1.27)
				)
				(hide yes)
			)
		)
		(property "Manufacturer" "YAGEO"
			(at 397.51 198.12 0)
			(effects
				(font
					(size 1.27 1.27)
					(thickness 0.15)
				)
				(justify left bottom)
				(hide yes)
			)
		)
		(property "MPN" "CC0402MRX5R5BB106"
			(at 394.97 198.12 0)
			(effects
				(font
					(size 1.27 1.27)
					(thickness 0.15)
				)
				(justify left bottom)
				(hide yes)
			)
		)
		(property "Val" "10u"
			(at 377.825 217.805 90)
			(effects
				(font
					(size 1.27 1.27)
					(thickness 0.15)
				)
				(justify right)
			)
		)
		(property "License" "Apache-2.0"
			(at 400.05 198.12 0)
			(effects
				(font
					(size 1.27 1.27)
					(thickness 0.15)
				)
				(justify left bottom)
				(hide yes)
			)
		)
		(property "Author" "Antmicro"
			(at 402.59 198.12 0)
			(effects
				(font
					(size 1.27 1.27)
					(thickness 0.15)
				)
				(justify left bottom)
				(hide yes)
			)
		)
		(property "Voltage" ""
			(at 405.13 198.12 0)
			(effects
				(font
					(size 1.27 1.27)
				)
				(justify left bottom)
				(hide yes)
			)
		)
		(property "Dielectric" ""
			(at 407.67 198.12 0)
			(effects
				(font
					(size 1.27 1.27)
				)
				(justify left bottom)
				(hide yes)
			)
		)
		(pin "1"
		)
		(pin "2"
		)
		(instances
			(project "artix-dc-scm"
				(path ""
					(reference "C103")
					(unit 1)
				)
			)
		)
	)
	(symbol
		(lib_id "antmicroResistors0402:R_0R_0402")
		(at 318.77 218.44 180)
		(unit 1)
		(exclude_from_sim no)
		(in_bom yes)
		(on_board yes)
		(dnp no)
		(property "Reference" "R185"
			(at 316.23 215.9 0)
			(effects
				(font
					(size 1.27 1.27)
				)
			)
		)
		(property "Value" "R_0R_0402"
			(at 298.45 205.74 0)
			(effects
				(font
					(size 1.27 1.27)
					(thickness 0.15)
				)
				(justify left bottom)
				(hide yes)
			)
		)
		(property "Footprint" "antmicro-footprints:R_0402_1005Metric"
			(at 298.45 203.2 0)
			(effects
				(font
					(size 1.27 1.27)
					(thickness 0.15)
				)
				(justify left bottom)
				(hide yes)
			)
		)
		(property "Datasheet" "https://industrial.panasonic.com/cdbs/www-data/pdf/RDA0000/AOA0000C301.pdf"
			(at 298.45 200.66 0)
			(effects
				(font
					(size 1.27 1.27)
					(thickness 0.15)
				)
				(justify left bottom)
				(hide yes)
			)
		)
		(property "Description" "SMD Chip Resistor, Jumper, 0 ohm, 100 mW, 0402 [1005 Metric], Thick Film, General Purpose"
			(at 318.77 218.44 0)
			(effects
				(font
					(size 1.27 1.27)
				)
				(hide yes)
			)
		)
		(property "Manufacturer" "Panasonic"
			(at 298.45 195.58 0)
			(effects
				(font
					(size 1.27 1.27)
					(thickness 0.15)
				)
				(justify left bottom)
				(hide yes)
			)
		)
		(property "MPN" "ERJ2GE0R00X"
			(at 298.45 198.12 0)
			(effects
				(font
					(size 1.27 1.27)
					(thickness 0.15)
				)
				(justify left bottom)
				(hide yes)
			)
		)
		(property "Val" "0R"
			(at 316.23 220.98 0)
			(effects
				(font
					(size 1.27 1.27)
					(thickness 0.15)
				)
			)
		)
		(property "License" "Apache-2.0"
			(at 298.45 193.04 0)
			(effects
				(font
					(size 1.27 1.27)
					(thickness 0.15)
				)
				(justify left bottom)
				(hide yes)
			)
		)
		(property "Author" "Antmicro"
			(at 298.45 190.5 0)
			(effects
				(font
					(size 1.27 1.27)
					(thickness 0.15)
				)
				(justify left bottom)
				(hide yes)
			)
		)
		(property "Tolerance" "~"
			(at 298.45 208.28 0)
			(effects
				(font
					(size 1.27 1.27)
				)
				(justify left bottom)
				(hide yes)
			)
		)
		(property "Current" "1A"
			(at 316.23 227.33 0)
			(effects
				(font
					(size 1.27 1.27)
					(thickness 0.15)
				)
				(hide yes)
			)
		)
		(pin "1"
		)
		(pin "2"
		)
		(instances
			(project "artix-dc-scm"
				(path ""
					(reference "R185")
					(unit 1)
				)
			)
		)
	)
	(symbol
		(lib_id "antmicroFixedInductors:L_470n_6.7A_Vishay-IHLP-1212AE-11")
		(at 346.71 212.09 0)
		(unit 1)
		(exclude_from_sim no)
		(in_bom yes)
		(on_board yes)
		(dnp no)
		(fields_autoplaced yes)
		(property "Reference" "L6"
			(at 349.25 207.01 0)
			(effects
				(font
					(size 1.27 1.27)
				)
			)
		)
		(property "Value" "L_470n_6.7A_Vishay-IHLP-1212AE-11"
			(at 360.68 214.63 0)
			(effects
				(font
					(size 1.27 1.27)
					(thickness 0.15)
				)
				(justify left bottom)
				(hide yes)
			)
		)
		(property "Footprint" "antmicro-footprints:L_Vishay-IHLP-1212AE"
			(at 360.68 219.71 0)
			(effects
				(font
					(size 1.27 1.27)
					(thickness 0.15)
				)
				(justify left bottom)
				(hide yes)
			)
		)
		(property "Datasheet" "https://www.vishay.com/docs/34300/ihlp-1212ae-11.pdf"
			(at 360.68 222.25 0)
			(effects
				(font
					(size 1.27 1.27)
					(thickness 0.15)
				)
				(justify left bottom)
				(hide yes)
			)
		)
		(property "Description" "Power Inductor (SMT), 470 nH, 6.7 A, Shielded, 6.7 A"
			(at 346.71 212.09 0)
			(effects
				(font
					(size 1.27 1.27)
				)
				(hide yes)
			)
		)
		(property "Manufacturer" "Vishay"
			(at 360.68 224.79 0)
			(effects
				(font
					(size 1.27 1.27)
					(thickness 0.15)
				)
				(justify left bottom)
				(hide yes)
			)
		)
		(property "MPN" "IHLP1212AEERR47M11"
			(at 360.68 227.33 0)
			(effects
				(font
					(size 1.27 1.27)
					(thickness 0.15)
				)
				(justify left bottom)
				(hide yes)
			)
		)
		(property "Val" "470n/6.7A"
			(at 349.25 209.55 0)
			(effects
				(font
					(size 1.27 1.27)
					(thickness 0.15)
				)
			)
		)
		(property "ISat" "6.7 A"
			(at 360.68 228.6 0)
			(effects
				(font
					(size 1.27 1.27)
				)
				(justify left)
				(hide yes)
			)
		)
		(property "IMax" "6.7 A"
			(at 360.68 232.41 0)
			(effects
				(font
					(size 1.27 1.27)
					(thickness 0.15)
				)
				(justify left bottom)
				(hide yes)
			)
		)
		(property "Size" "3.0x3.0"
			(at 360.68 234.95 0)
			(effects
				(font
					(size 1.27 1.27)
					(thickness 0.15)
				)
				(justify left bottom)
				(hide yes)
			)
		)
		(property "Author" "Antmicro"
			(at 360.68 237.49 0)
			(effects
				(font
					(size 1.27 1.27)
					(thickness 0.15)
				)
				(justify left bottom)
				(hide yes)
			)
		)
		(property "License" "Apache-2.0"
			(at 360.68 240.03 0)
			(effects
				(font
					(size 1.27 1.27)
					(thickness 0.15)
				)
				(justify left bottom)
				(hide yes)
			)
		)
		(pin "1"
		)
		(pin "2"
		)
		(instances
			(project "artix-dc-scm"
				(path ""
					(reference "L6")
					(unit 1)
				)
			)
		)
	)
	(symbol
		(lib_id "antmicroResistors0603:R_0R_0603")
		(at 388.62 212.09 180)
		(unit 1)
		(exclude_from_sim no)
		(in_bom yes)
		(on_board yes)
		(dnp no)
		(property "Reference" "R188"
			(at 386.08 209.55 0)
			(effects
				(font
					(size 1.27 1.27)
				)
			)
		)
		(property "Value" "R_0R_0603"
			(at 368.3 199.39 0)
			(effects
				(font
					(size 1.27 1.27)
					(thickness 0.15)
				)
				(justify left bottom)
				(hide yes)
			)
		)
		(property "Footprint" "antmicro-footprints:R_0603_1608Metric"
			(at 368.3 196.85 0)
			(effects
				(font
					(size 1.27 1.27)
					(thickness 0.15)
				)
				(justify left bottom)
				(hide yes)
			)
		)
		(property "Datasheet" "https://www.bourns.com/docs/product-datasheets/cr.pdf?sfvrsn=574d41f6_14"
			(at 368.3 194.31 0)
			(effects
				(font
					(size 1.27 1.27)
					(thickness 0.15)
				)
				(justify left bottom)
				(hide yes)
			)
		)
		(property "Description" "Zero Ohm Resistor, Jumper, 0603 [1608 Metric], Thick Film, 100 mW, 1 A, Surface Mount Device, CR"
			(at 388.62 212.09 0)
			(effects
				(font
					(size 1.27 1.27)
				)
				(hide yes)
			)
		)
		(property "Manufacturer" "Bourns"
			(at 368.3 189.23 0)
			(effects
				(font
					(size 1.27 1.27)
					(thickness 0.15)
				)
				(justify left bottom)
				(hide yes)
			)
		)
		(property "MPN" "CR0603-J/-000ELF"
			(at 368.3 191.77 0)
			(effects
				(font
					(size 1.27 1.27)
					(thickness 0.15)
				)
				(justify left bottom)
				(hide yes)
			)
		)
		(property "Val" "0R"
			(at 386.08 214.63 0)
			(effects
				(font
					(size 1.27 1.27)
					(thickness 0.15)
				)
			)
		)
		(property "License" "Apache-2.0"
			(at 368.3 186.69 0)
			(effects
				(font
					(size 1.27 1.27)
					(thickness 0.15)
				)
				(justify left bottom)
				(hide yes)
			)
		)
		(property "Author" "Antmicro"
			(at 368.3 184.15 0)
			(effects
				(font
					(size 1.27 1.27)
					(thickness 0.15)
				)
				(justify left bottom)
				(hide yes)
			)
		)
		(property "Tolerance" "~"
			(at 368.3 201.93 0)
			(effects
				(font
					(size 1.27 1.27)
				)
				(justify left bottom)
				(hide yes)
			)
		)
		(property "Current" "1A"
			(at 386.08 208.28 0)
			(effects
				(font
					(size 1.27 1.27)
					(thickness 0.15)
				)
				(hide yes)
			)
		)
		(pin "1"
		)
		(pin "2"
		)
		(instances
			(project "artix-dc-scm"
				(path ""
					(reference "R188")
					(unit 1)
				)
			)
		)
	)
	(symbol
		(lib_id "antmicroCapacitors0402:C_10u_0402")
		(at 62.23 208.28 90)
		(unit 1)
		(exclude_from_sim no)
		(in_bom yes)
		(on_board yes)
		(dnp no)
		(property "Reference" "C250"
			(at 62.865 203.835 90)
			(effects
				(font
					(size 1.27 1.27)
				)
				(justify right)
			)
		)
		(property "Value" "C_10u_0402"
			(at 72.39 187.96 0)
			(effects
				(font
					(size 1.27 1.27)
					(thickness 0.15)
				)
				(justify left bottom)
				(hide yes)
			)
		)
		(property "Footprint" "antmicro-footprints:C_0402_1005Metric"
			(at 74.93 187.96 0)
			(effects
				(font
					(size 1.27 1.27)
					(thickness 0.15)
				)
				(justify left bottom)
				(hide yes)
			)
		)
		(property "Datasheet" "https://www.yageo.com/en/Chart/Download/pdf/CC0402MRX5R5BB106"
			(at 77.47 187.96 0)
			(effects
				(font
					(size 1.27 1.27)
					(thickness 0.15)
				)
				(justify left bottom)
				(hide yes)
			)
		)
		(property "Description" "SMD Multilayer Ceramic Capacitor, 10 µF, 6.3 V, 0402 [1005 Metric], ± 20%, X5R, CC Series"
			(at 62.23 208.28 0)
			(effects
				(font
					(size 1.27 1.27)
				)
				(hide yes)
			)
		)
		(property "Manufacturer" "YAGEO"
			(at 82.55 187.96 0)
			(effects
				(font
					(size 1.27 1.27)
					(thickness 0.15)
				)
				(justify left bottom)
				(hide yes)
			)
		)
		(property "MPN" "CC0402MRX5R5BB106"
			(at 80.01 187.96 0)
			(effects
				(font
					(size 1.27 1.27)
					(thickness 0.15)
				)
				(justify left bottom)
				(hide yes)
			)
		)
		(property "Val" "10u"
			(at 62.865 207.645 90)
			(effects
				(font
					(size 1.27 1.27)
					(thickness 0.15)
				)
				(justify right)
			)
		)
		(property "License" "Apache-2.0"
			(at 85.09 187.96 0)
			(effects
				(font
					(size 1.27 1.27)
					(thickness 0.15)
				)
				(justify left bottom)
				(hide yes)
			)
		)
		(property "Author" "Antmicro"
			(at 87.63 187.96 0)
			(effects
				(font
					(size 1.27 1.27)
					(thickness 0.15)
				)
				(justify left bottom)
				(hide yes)
			)
		)
		(property "Voltage" ""
			(at 90.17 187.96 0)
			(effects
				(font
					(size 1.27 1.27)
				)
				(justify left bottom)
				(hide yes)
			)
		)
		(property "Dielectric" ""
			(at 92.71 187.96 0)
			(effects
				(font
					(size 1.27 1.27)
				)
				(justify left bottom)
				(hide yes)
			)
		)
		(pin "1"
		)
		(pin "2"
		)
		(instances
			(project "artix-dc-scm"
				(path ""
					(reference "C250")
					(unit 1)
				)
			)
		)
	)
	(symbol
		(lib_id "antmicroResistors0402:R_0R_0402")
		(at 318.77 129.54 180)
		(unit 1)
		(exclude_from_sim no)
		(in_bom yes)
		(on_board yes)
		(dnp no)
		(property "Reference" "R138"
			(at 316.23 127 0)
			(effects
				(font
					(size 1.27 1.27)
				)
			)
		)
		(property "Value" "R_0R_0402"
			(at 298.45 116.84 0)
			(effects
				(font
					(size 1.27 1.27)
					(thickness 0.15)
				)
				(justify left bottom)
				(hide yes)
			)
		)
		(property "Footprint" "antmicro-footprints:R_0402_1005Metric"
			(at 298.45 114.3 0)
			(effects
				(font
					(size 1.27 1.27)
					(thickness 0.15)
				)
				(justify left bottom)
				(hide yes)
			)
		)
		(property "Datasheet" "https://industrial.panasonic.com/cdbs/www-data/pdf/RDA0000/AOA0000C301.pdf"
			(at 298.45 111.76 0)
			(effects
				(font
					(size 1.27 1.27)
					(thickness 0.15)
				)
				(justify left bottom)
				(hide yes)
			)
		)
		(property "Description" "SMD Chip Resistor, Jumper, 0 ohm, 100 mW, 0402 [1005 Metric], Thick Film, General Purpose"
			(at 318.77 129.54 0)
			(effects
				(font
					(size 1.27 1.27)
				)
				(hide yes)
			)
		)
		(property "Manufacturer" "Panasonic"
			(at 298.45 106.68 0)
			(effects
				(font
					(size 1.27 1.27)
					(thickness 0.15)
				)
				(justify left bottom)
				(hide yes)
			)
		)
		(property "MPN" "ERJ2GE0R00X"
			(at 298.45 109.22 0)
			(effects
				(font
					(size 1.27 1.27)
					(thickness 0.15)
				)
				(justify left bottom)
				(hide yes)
			)
		)
		(property "Val" "0R"
			(at 316.23 132.08 0)
			(effects
				(font
					(size 1.27 1.27)
					(thickness 0.15)
				)
			)
		)
		(property "License" "Apache-2.0"
			(at 298.45 104.14 0)
			(effects
				(font
					(size 1.27 1.27)
					(thickness 0.15)
				)
				(justify left bottom)
				(hide yes)
			)
		)
		(property "Author" "Antmicro"
			(at 298.45 101.6 0)
			(effects
				(font
					(size 1.27 1.27)
					(thickness 0.15)
				)
				(justify left bottom)
				(hide yes)
			)
		)
		(property "Tolerance" "~"
			(at 298.45 119.38 0)
			(effects
				(font
					(size 1.27 1.27)
				)
				(justify left bottom)
				(hide yes)
			)
		)
		(property "Current" "1A"
			(at 316.23 138.43 0)
			(effects
				(font
					(size 1.27 1.27)
					(thickness 0.15)
				)
				(hide yes)
			)
		)
		(pin "1"
		)
		(pin "2"
		)
		(instances
			(project "artix-dc-scm"
				(path ""
					(reference "R138")
					(unit 1)
				)
			)
		)
	)
	(symbol
		(lib_id "antmicroResistors0402:R_100k_0402")
		(at 62.23 184.15 270)
		(unit 1)
		(exclude_from_sim no)
		(in_bom yes)
		(on_board yes)
		(dnp no)
		(property "Reference" "R68"
			(at 63.5 185.42 90)
			(effects
				(font
					(size 1.27 1.27)
				)
				(justify left)
			)
		)
		(property "Value" "R_100k_0402"
			(at 49.53 204.47 0)
			(effects
				(font
					(size 1.27 1.27)
					(thickness 0.15)
				)
				(justify left bottom)
				(hide yes)
			)
		)
		(property "Footprint" "antmicro-footprints:R_0402_1005Metric"
			(at 46.99 204.47 0)
			(effects
				(font
					(size 1.27 1.27)
					(thickness 0.15)
				)
				(justify left bottom)
				(hide yes)
			)
		)
		(property "Datasheet" "https://www.bourns.com/docs/product-datasheets/cr.pdf"
			(at 44.45 204.47 0)
			(effects
				(font
					(size 1.27 1.27)
					(thickness 0.15)
				)
				(justify left bottom)
				(hide yes)
			)
		)
		(property "Description" "SMD Chip Resistor, 100 kohm, ± 1%, 62.5 mW, 0402 [1005 Metric], Thick Film, General Purpose"
			(at 62.23 184.15 0)
			(effects
				(font
					(size 1.27 1.27)
				)
				(hide yes)
			)
		)
		(property "Manufacturer" "Bourns"
			(at 39.37 204.47 0)
			(effects
				(font
					(size 1.27 1.27)
					(thickness 0.15)
				)
				(justify left bottom)
				(hide yes)
			)
		)
		(property "MPN" "CR0402-FX-1003GLF"
			(at 41.91 204.47 0)
			(effects
				(font
					(size 1.27 1.27)
					(thickness 0.15)
				)
				(justify left bottom)
				(hide yes)
			)
		)
		(property "Val" "100k"
			(at 63.5 187.96 90)
			(effects
				(font
					(size 1.27 1.27)
					(thickness 0.15)
				)
				(justify left)
			)
		)
		(property "License" "Apache-2.0"
			(at 36.83 204.47 0)
			(effects
				(font
					(size 1.27 1.27)
					(thickness 0.15)
				)
				(justify left bottom)
				(hide yes)
			)
		)
		(property "Author" "Antmicro"
			(at 34.29 204.47 0)
			(effects
				(font
					(size 1.27 1.27)
					(thickness 0.15)
				)
				(justify left bottom)
				(hide yes)
			)
		)
		(property "Tolerance" "1%"
			(at 52.07 204.47 0)
			(effects
				(font
					(size 1.27 1.27)
				)
				(justify left bottom)
				(hide yes)
			)
		)
		(pin "1"
		)
		(pin "2"
		)
		(instances
			(project "artix-dc-scm"
				(path ""
					(reference "R68")
					(unit 1)
				)
			)
		)
	)
	(symbol
		(lib_id "antmicroResistors0402:R_100k_0402")
		(at 105.41 184.15 270)
		(unit 1)
		(exclude_from_sim no)
		(in_bom yes)
		(on_board yes)
		(dnp no)
		(property "Reference" "R63"
			(at 106.68 185.42 90)
			(effects
				(font
					(size 1.27 1.27)
				)
				(justify left)
			)
		)
		(property "Value" "R_100k_0402"
			(at 92.71 204.47 0)
			(effects
				(font
					(size 1.27 1.27)
					(thickness 0.15)
				)
				(justify left bottom)
				(hide yes)
			)
		)
		(property "Footprint" "antmicro-footprints:R_0402_1005Metric"
			(at 90.17 204.47 0)
			(effects
				(font
					(size 1.27 1.27)
					(thickness 0.15)
				)
				(justify left bottom)
				(hide yes)
			)
		)
		(property "Datasheet" "https://www.bourns.com/docs/product-datasheets/cr.pdf"
			(at 87.63 204.47 0)
			(effects
				(font
					(size 1.27 1.27)
					(thickness 0.15)
				)
				(justify left bottom)
				(hide yes)
			)
		)
		(property "Description" "SMD Chip Resistor, 100 kohm, ± 1%, 62.5 mW, 0402 [1005 Metric], Thick Film, General Purpose"
			(at 105.41 184.15 0)
			(effects
				(font
					(size 1.27 1.27)
				)
				(hide yes)
			)
		)
		(property "Manufacturer" "Bourns"
			(at 82.55 204.47 0)
			(effects
				(font
					(size 1.27 1.27)
					(thickness 0.15)
				)
				(justify left bottom)
				(hide yes)
			)
		)
		(property "MPN" "CR0402-FX-1003GLF"
			(at 85.09 204.47 0)
			(effects
				(font
					(size 1.27 1.27)
					(thickness 0.15)
				)
				(justify left bottom)
				(hide yes)
			)
		)
		(property "Val" "100k"
			(at 106.68 187.96 90)
			(effects
				(font
					(size 1.27 1.27)
					(thickness 0.15)
				)
				(justify left)
			)
		)
		(property "License" "Apache-2.0"
			(at 80.01 204.47 0)
			(effects
				(font
					(size 1.27 1.27)
					(thickness 0.15)
				)
				(justify left bottom)
				(hide yes)
			)
		)
		(property "Author" "Antmicro"
			(at 77.47 204.47 0)
			(effects
				(font
					(size 1.27 1.27)
					(thickness 0.15)
				)
				(justify left bottom)
				(hide yes)
			)
		)
		(property "Tolerance" "1%"
			(at 95.25 204.47 0)
			(effects
				(font
					(size 1.27 1.27)
				)
				(justify left bottom)
				(hide yes)
			)
		)
		(pin "1"
		)
		(pin "2"
		)
		(instances
			(project "artix-dc-scm"
				(path ""
					(reference "R63")
					(unit 1)
				)
			)
		)
	)
	(symbol
		(lib_id "antmicroWire2BoardConnectors:Molex_Pico-Lock_1x2_504050-0291")
		(at 35.56 54.61 0)
		(mirror y)
		(unit 1)
		(exclude_from_sim no)
		(in_bom yes)
		(on_board yes)
		(dnp no)
		(fields_autoplaced yes)
		(property "Reference" "J5"
			(at 30.48 48.26 0)
			(effects
				(font
					(size 1.27 1.27)
				)
			)
		)
		(property "Value" "Molex_Pico-Lock_1x2_504050-0291"
			(at 26.67 57.15 0)
			(effects
				(font
					(size 1.27 1.27)
					(thickness 0.15)
				)
				(justify left bottom)
				(hide yes)
			)
		)
		(property "Footprint" "antmicro-footprints:Conn_Molex_Pico-Lock_1x2_504050-0291"
			(at 26.67 59.69 0)
			(effects
				(font
					(size 1.27 1.27)
					(thickness 0.15)
				)
				(justify left bottom)
				(hide yes)
			)
		)
		(property "Datasheet" "https://www.molex.com/en-us/products/part-detail-pdf/5040500291?display=pdf"
			(at 26.67 62.23 0)
			(effects
				(font
					(size 1.27 1.27)
					(thickness 0.15)
				)
				(justify left bottom)
				(hide yes)
			)
		)
		(property "Description" "Connector Header Surface Mount, Right Angle 2 position 0.059\" (1.50mm)"
			(at 35.56 54.61 0)
			(effects
				(font
					(size 1.27 1.27)
				)
				(hide yes)
			)
		)
		(property "MPN" "504050-0291"
			(at 30.48 50.8 0)
			(effects
				(font
					(size 1.27 1.27)
					(thickness 0.15)
				)
			)
		)
		(property "Manufacturer" "Molex"
			(at 26.67 64.77 0)
			(effects
				(font
					(size 1.27 1.27)
					(thickness 0.15)
				)
				(justify left bottom)
				(hide yes)
			)
		)
		(property "Author" "Antmicro"
			(at 26.67 69.85 0)
			(effects
				(font
					(size 1.27 1.27)
					(thickness 0.15)
				)
				(justify left bottom)
				(hide yes)
			)
		)
		(property "License" "Apache-2.0"
			(at 26.67 72.39 0)
			(effects
				(font
					(size 1.27 1.27)
					(thickness 0.15)
				)
				(justify left bottom)
				(hide yes)
			)
		)
		(pin "1"
		)
		(pin "2"
		)
		(pin "MP2"
		)
		(pin "MP1"
		)
		(instances
			(project "artix-dc-scm"
				(path ""
					(reference "J5")
					(unit 1)
				)
			)
		)
	)
	(symbol
		(lib_id "antmicroResistors0402:R_0R_0402")
		(at 318.77 173.99 180)
		(unit 1)
		(exclude_from_sim no)
		(in_bom yes)
		(on_board yes)
		(dnp no)
		(property "Reference" "R16"
			(at 316.23 171.45 0)
			(effects
				(font
					(size 1.27 1.27)
				)
			)
		)
		(property "Value" "R_0R_0402"
			(at 298.45 161.29 0)
			(effects
				(font
					(size 1.27 1.27)
					(thickness 0.15)
				)
				(justify left bottom)
				(hide yes)
			)
		)
		(property "Footprint" "antmicro-footprints:R_0402_1005Metric"
			(at 298.45 158.75 0)
			(effects
				(font
					(size 1.27 1.27)
					(thickness 0.15)
				)
				(justify left bottom)
				(hide yes)
			)
		)
		(property "Datasheet" "https://industrial.panasonic.com/cdbs/www-data/pdf/RDA0000/AOA0000C301.pdf"
			(at 298.45 156.21 0)
			(effects
				(font
					(size 1.27 1.27)
					(thickness 0.15)
				)
				(justify left bottom)
				(hide yes)
			)
		)
		(property "Description" "SMD Chip Resistor, Jumper, 0 ohm, 100 mW, 0402 [1005 Metric], Thick Film, General Purpose"
			(at 318.77 173.99 0)
			(effects
				(font
					(size 1.27 1.27)
				)
				(hide yes)
			)
		)
		(property "Manufacturer" "Panasonic"
			(at 298.45 151.13 0)
			(effects
				(font
					(size 1.27 1.27)
					(thickness 0.15)
				)
				(justify left bottom)
				(hide yes)
			)
		)
		(property "MPN" "ERJ2GE0R00X"
			(at 298.45 153.67 0)
			(effects
				(font
					(size 1.27 1.27)
					(thickness 0.15)
				)
				(justify left bottom)
				(hide yes)
			)
		)
		(property "Val" "0R"
			(at 316.23 176.53 0)
			(effects
				(font
					(size 1.27 1.27)
					(thickness 0.15)
				)
			)
		)
		(property "License" "Apache-2.0"
			(at 298.45 148.59 0)
			(effects
				(font
					(size 1.27 1.27)
					(thickness 0.15)
				)
				(justify left bottom)
				(hide yes)
			)
		)
		(property "Author" "Antmicro"
			(at 298.45 146.05 0)
			(effects
				(font
					(size 1.27 1.27)
					(thickness 0.15)
				)
				(justify left bottom)
				(hide yes)
			)
		)
		(property "Tolerance" "~"
			(at 298.45 163.83 0)
			(effects
				(font
					(size 1.27 1.27)
				)
				(justify left bottom)
				(hide yes)
			)
		)
		(property "Current" "1A"
			(at 316.23 182.245 0)
			(effects
				(font
					(size 1.27 1.27)
					(thickness 0.15)
				)
				(hide yes)
			)
		)
		(pin "1"
		)
		(pin "2"
		)
		(instances
			(project "artix-dc-scm"
				(path ""
					(reference "R16")
					(unit 1)
				)
			)
		)
	)
	(symbol
		(lib_id "antmicroResistors0402:R_100k_0402")
		(at 360.68 213.36 270)
		(unit 1)
		(exclude_from_sim no)
		(in_bom yes)
		(on_board yes)
		(dnp no)
		(property "Reference" "R186"
			(at 361.95 214.63 90)
			(effects
				(font
					(size 1.27 1.27)
				)
				(justify left)
			)
		)
		(property "Value" "R_100k_0402"
			(at 347.98 233.68 0)
			(effects
				(font
					(size 1.27 1.27)
					(thickness 0.15)
				)
				(justify left bottom)
				(hide yes)
			)
		)
		(property "Footprint" "antmicro-footprints:R_0402_1005Metric"
			(at 345.44 233.68 0)
			(effects
				(font
					(size 1.27 1.27)
					(thickness 0.15)
				)
				(justify left bottom)
				(hide yes)
			)
		)
		(property "Datasheet" "https://www.bourns.com/docs/product-datasheets/cr.pdf"
			(at 342.9 233.68 0)
			(effects
				(font
					(size 1.27 1.27)
					(thickness 0.15)
				)
				(justify left bottom)
				(hide yes)
			)
		)
		(property "Description" "SMD Chip Resistor, 100 kohm, ± 1%, 62.5 mW, 0402 [1005 Metric], Thick Film, General Purpose"
			(at 360.68 213.36 0)
			(effects
				(font
					(size 1.27 1.27)
				)
				(hide yes)
			)
		)
		(property "Manufacturer" "Bourns"
			(at 337.82 233.68 0)
			(effects
				(font
					(size 1.27 1.27)
					(thickness 0.15)
				)
				(justify left bottom)
				(hide yes)
			)
		)
		(property "MPN" "CR0402-FX-1003GLF"
			(at 340.36 233.68 0)
			(effects
				(font
					(size 1.27 1.27)
					(thickness 0.15)
				)
				(justify left bottom)
				(hide yes)
			)
		)
		(property "Val" "100k"
			(at 361.95 217.17 90)
			(effects
				(font
					(size 1.27 1.27)
					(thickness 0.15)
				)
				(justify left)
			)
		)
		(property "License" "Apache-2.0"
			(at 335.28 233.68 0)
			(effects
				(font
					(size 1.27 1.27)
					(thickness 0.15)
				)
				(justify left bottom)
				(hide yes)
			)
		)
		(property "Author" "Antmicro"
			(at 332.74 233.68 0)
			(effects
				(font
					(size 1.27 1.27)
					(thickness 0.15)
				)
				(justify left bottom)
				(hide yes)
			)
		)
		(property "Tolerance" "1%"
			(at 350.52 233.68 0)
			(effects
				(font
					(size 1.27 1.27)
				)
				(justify left bottom)
				(hide yes)
			)
		)
		(pin "1"
		)
		(pin "2"
		)
		(instances
			(project "artix-dc-scm"
				(path ""
					(reference "R186")
					(unit 1)
				)
			)
		)
	)
	(symbol
		(lib_id "antmicroResistors0402:R_100k_0402")
		(at 113.03 184.15 270)
		(unit 1)
		(exclude_from_sim no)
		(in_bom yes)
		(on_board yes)
		(dnp no)
		(property "Reference" "R64"
			(at 114.3 185.42 90)
			(effects
				(font
					(size 1.27 1.27)
				)
				(justify left)
			)
		)
		(property "Value" "R_100k_0402"
			(at 100.33 204.47 0)
			(effects
				(font
					(size 1.27 1.27)
					(thickness 0.15)
				)
				(justify left bottom)
				(hide yes)
			)
		)
		(property "Footprint" "antmicro-footprints:R_0402_1005Metric"
			(at 97.79 204.47 0)
			(effects
				(font
					(size 1.27 1.27)
					(thickness 0.15)
				)
				(justify left bottom)
				(hide yes)
			)
		)
		(property "Datasheet" "https://www.bourns.com/docs/product-datasheets/cr.pdf"
			(at 95.25 204.47 0)
			(effects
				(font
					(size 1.27 1.27)
					(thickness 0.15)
				)
				(justify left bottom)
				(hide yes)
			)
		)
		(property "Description" "SMD Chip Resistor, 100 kohm, ± 1%, 62.5 mW, 0402 [1005 Metric], Thick Film, General Purpose"
			(at 113.03 184.15 0)
			(effects
				(font
					(size 1.27 1.27)
				)
				(hide yes)
			)
		)
		(property "Manufacturer" "Bourns"
			(at 90.17 204.47 0)
			(effects
				(font
					(size 1.27 1.27)
					(thickness 0.15)
				)
				(justify left bottom)
				(hide yes)
			)
		)
		(property "MPN" "CR0402-FX-1003GLF"
			(at 92.71 204.47 0)
			(effects
				(font
					(size 1.27 1.27)
					(thickness 0.15)
				)
				(justify left bottom)
				(hide yes)
			)
		)
		(property "Val" "100k"
			(at 114.3 187.96 90)
			(effects
				(font
					(size 1.27 1.27)
					(thickness 0.15)
				)
				(justify left)
			)
		)
		(property "License" "Apache-2.0"
			(at 87.63 204.47 0)
			(effects
				(font
					(size 1.27 1.27)
					(thickness 0.15)
				)
				(justify left bottom)
				(hide yes)
			)
		)
		(property "Author" "Antmicro"
			(at 85.09 204.47 0)
			(effects
				(font
					(size 1.27 1.27)
					(thickness 0.15)
				)
				(justify left bottom)
				(hide yes)
			)
		)
		(property "Tolerance" "1%"
			(at 102.87 204.47 0)
			(effects
				(font
					(size 1.27 1.27)
				)
				(justify left bottom)
				(hide yes)
			)
		)
		(pin "1"
		)
		(pin "2"
		)
		(instances
			(project "artix-dc-scm"
				(path ""
					(reference "R64")
					(unit 1)
				)
			)
		)
	)
	(symbol
		(lib_id "antmicroResistors0402:R_100k_0402")
		(at 120.65 184.15 270)
		(unit 1)
		(exclude_from_sim no)
		(in_bom yes)
		(on_board yes)
		(dnp no)
		(property "Reference" "R65"
			(at 121.92 185.42 90)
			(effects
				(font
					(size 1.27 1.27)
				)
				(justify left)
			)
		)
		(property "Value" "R_100k_0402"
			(at 107.95 204.47 0)
			(effects
				(font
					(size 1.27 1.27)
					(thickness 0.15)
				)
				(justify left bottom)
				(hide yes)
			)
		)
		(property "Footprint" "antmicro-footprints:R_0402_1005Metric"
			(at 105.41 204.47 0)
			(effects
				(font
					(size 1.27 1.27)
					(thickness 0.15)
				)
				(justify left bottom)
				(hide yes)
			)
		)
		(property "Datasheet" "https://www.bourns.com/docs/product-datasheets/cr.pdf"
			(at 102.87 204.47 0)
			(effects
				(font
					(size 1.27 1.27)
					(thickness 0.15)
				)
				(justify left bottom)
				(hide yes)
			)
		)
		(property "Description" "SMD Chip Resistor, 100 kohm, ± 1%, 62.5 mW, 0402 [1005 Metric], Thick Film, General Purpose"
			(at 120.65 184.15 0)
			(effects
				(font
					(size 1.27 1.27)
				)
				(hide yes)
			)
		)
		(property "Manufacturer" "Bourns"
			(at 97.79 204.47 0)
			(effects
				(font
					(size 1.27 1.27)
					(thickness 0.15)
				)
				(justify left bottom)
				(hide yes)
			)
		)
		(property "MPN" "CR0402-FX-1003GLF"
			(at 100.33 204.47 0)
			(effects
				(font
					(size 1.27 1.27)
					(thickness 0.15)
				)
				(justify left bottom)
				(hide yes)
			)
		)
		(property "Val" "100k"
			(at 121.92 187.96 90)
			(effects
				(font
					(size 1.27 1.27)
					(thickness 0.15)
				)
				(justify left)
			)
		)
		(property "License" "Apache-2.0"
			(at 95.25 204.47 0)
			(effects
				(font
					(size 1.27 1.27)
					(thickness 0.15)
				)
				(justify left bottom)
				(hide yes)
			)
		)
		(property "Author" "Antmicro"
			(at 92.71 204.47 0)
			(effects
				(font
					(size 1.27 1.27)
					(thickness 0.15)
				)
				(justify left bottom)
				(hide yes)
			)
		)
		(property "Tolerance" "1%"
			(at 110.49 204.47 0)
			(effects
				(font
					(size 1.27 1.27)
				)
				(justify left bottom)
				(hide yes)
			)
		)
		(pin "1"
		)
		(pin "2"
		)
		(instances
			(project "artix-dc-scm"
				(path ""
					(reference "R65")
					(unit 1)
				)
			)
		)
	)
	(symbol
		(lib_id "antmicroResistors0402:R_10k_0402")
		(at 226.06 38.1 270)
		(unit 1)
		(exclude_from_sim no)
		(in_bom yes)
		(on_board yes)
		(dnp no)
		(property "Reference" "R189"
			(at 227.33 39.37 90)
			(effects
				(font
					(size 1.27 1.27)
				)
				(justify left)
			)
		)
		(property "Value" "R_10k_0402"
			(at 213.36 58.42 0)
			(effects
				(font
					(size 1.27 1.27)
					(thickness 0.15)
				)
				(justify left bottom)
				(hide yes)
			)
		)
		(property "Footprint" "antmicro-footprints:R_0402_1005Metric"
			(at 210.82 58.42 0)
			(effects
				(font
					(size 1.27 1.27)
					(thickness 0.15)
				)
				(justify left bottom)
				(hide yes)
			)
		)
		(property "Datasheet" "https://www.bourns.com/docs/product-datasheets/cr.pdf"
			(at 208.28 58.42 0)
			(effects
				(font
					(size 1.27 1.27)
					(thickness 0.15)
				)
				(justify left bottom)
				(hide yes)
			)
		)
		(property "Description" "SMD Chip Resistor, 10 kohm, ± 1%, 62.5 mW, 0402 [1005 Metric], Thick Film, General Purpose"
			(at 226.06 38.1 0)
			(effects
				(font
					(size 1.27 1.27)
				)
				(hide yes)
			)
		)
		(property "Manufacturer" "Bourns"
			(at 203.2 58.42 0)
			(effects
				(font
					(size 1.27 1.27)
					(thickness 0.15)
				)
				(justify left bottom)
				(hide yes)
			)
		)
		(property "MPN" "CR0402-FX-1002GLF"
			(at 205.74 58.42 0)
			(effects
				(font
					(size 1.27 1.27)
					(thickness 0.15)
				)
				(justify left bottom)
				(hide yes)
			)
		)
		(property "Val" "10k"
			(at 227.33 41.91 90)
			(effects
				(font
					(size 1.27 1.27)
					(thickness 0.15)
				)
				(justify left)
			)
		)
		(property "License" "Apache-2.0"
			(at 200.66 58.42 0)
			(effects
				(font
					(size 1.27 1.27)
					(thickness 0.15)
				)
				(justify left bottom)
				(hide yes)
			)
		)
		(property "Author" "Antmicro"
			(at 198.12 58.42 0)
			(effects
				(font
					(size 1.27 1.27)
					(thickness 0.15)
				)
				(justify left bottom)
				(hide yes)
			)
		)
		(property "Tolerance" "1%"
			(at 215.9 58.42 0)
			(effects
				(font
					(size 1.27 1.27)
				)
				(justify left bottom)
				(hide yes)
			)
		)
		(pin "1"
		)
		(pin "2"
		)
		(instances
			(project "artix-dc-scm"
				(path ""
					(reference "R189")
					(unit 1)
				)
			)
		)
	)
	(symbol
		(lib_id "antmicroResistors0402:R_1k_0402")
		(at 260.35 34.29 0)
		(unit 1)
		(exclude_from_sim no)
		(in_bom yes)
		(on_board yes)
		(dnp no)
		(property "Reference" "R190"
			(at 262.89 31.75 0)
			(effects
				(font
					(size 1.27 1.27)
				)
			)
		)
		(property "Value" "R_1k_0402"
			(at 280.67 46.99 0)
			(effects
				(font
					(size 1.27 1.27)
					(thickness 0.15)
				)
				(justify left bottom)
				(hide yes)
			)
		)
		(property "Footprint" "antmicro-footprints:R_0402_1005Metric"
			(at 280.67 49.53 0)
			(effects
				(font
					(size 1.27 1.27)
					(thickness 0.15)
				)
				(justify left bottom)
				(hide yes)
			)
		)
		(property "Datasheet" "https://www.bourns.com/docs/product-datasheets/cr.pdf"
			(at 280.67 52.07 0)
			(effects
				(font
					(size 1.27 1.27)
					(thickness 0.15)
				)
				(justify left bottom)
				(hide yes)
			)
		)
		(property "Description" "SMD Chip Resistor, 1 kohm, ± 1%, 63 mW, 0402 [1005 Metric], Thick Film, General Purpose"
			(at 260.35 34.29 0)
			(effects
				(font
					(size 1.27 1.27)
				)
				(hide yes)
			)
		)
		(property "Manufacturer" "Bourns"
			(at 280.67 57.15 0)
			(effects
				(font
					(size 1.27 1.27)
					(thickness 0.15)
				)
				(justify left bottom)
				(hide yes)
			)
		)
		(property "MPN" "CR0402-FX-1001GLF"
			(at 280.67 54.61 0)
			(effects
				(font
					(size 1.27 1.27)
					(thickness 0.15)
				)
				(justify left bottom)
				(hide yes)
			)
		)
		(property "Val" "1k"
			(at 262.89 36.83 0)
			(effects
				(font
					(size 1.27 1.27)
					(thickness 0.15)
				)
			)
		)
		(property "License" "Apache-2.0"
			(at 280.67 59.69 0)
			(effects
				(font
					(size 1.27 1.27)
					(thickness 0.15)
				)
				(justify left bottom)
				(hide yes)
			)
		)
		(property "Author" "Antmicro"
			(at 280.67 62.23 0)
			(effects
				(font
					(size 1.27 1.27)
					(thickness 0.15)
				)
				(justify left bottom)
				(hide yes)
			)
		)
		(property "Tolerance" "1%"
			(at 280.67 44.45 0)
			(effects
				(font
					(size 1.27 1.27)
				)
				(justify left bottom)
				(hide yes)
			)
		)
		(pin "1"
		)
		(pin "2"
		)
		(instances
			(project "artix-dc-scm"
				(path ""
					(reference "R190")
					(unit 1)
				)
			)
		)
	)
	(symbol
		(lib_id "antmicropower:GND")
		(at 238.76 48.26 0)
		(unit 1)
		(exclude_from_sim no)
		(in_bom yes)
		(on_board yes)
		(dnp no)
		(property "Reference" "#PWR06"
			(at 238.76 54.61 0)
			(effects
				(font
					(size 1.27 1.27)
				)
				(hide yes)
			)
		)
		(property "Value" "GND"
			(at 238.76 52.07 0)
			(effects
				(font
					(size 1.27 1.27)
				)
			)
		)
		(property "Footprint" ""
			(at 238.76 48.26 0)
			(effects
				(font
					(size 1.27 1.27)
				)
				(hide yes)
			)
		)
		(property "Datasheet" ""
			(at 238.76 48.26 0)
			(effects
				(font
					(size 1.27 1.27)
				)
				(hide yes)
			)
		)
		(property "Description" ""
			(at 238.76 48.26 0)
			(effects
				(font
					(size 1.27 1.27)
				)
				(hide yes)
			)
		)
		(property "Author" "Antmicro"
			(at 247.65 55.88 0)
			(effects
				(font
					(size 1.27 1.27)
					(thickness 0.15)
				)
				(justify left bottom)
				(hide yes)
			)
		)
		(property "License" "Apache-2.0"
			(at 247.65 58.42 0)
			(effects
				(font
					(size 1.27 1.27)
					(thickness 0.15)
				)
				(justify left bottom)
				(hide yes)
			)
		)
		(pin "1"
		)
		(instances
			(project "artix-dc-scm"
				(path ""
					(reference "#PWR06")
					(unit 1)
				)
			)
		)
	)
	(symbol
		(lib_id "antmicroTransistorsFETsMOSFETsSingle:BSS138PW")
		(at 231.14 44.45 0)
		(unit 1)
		(exclude_from_sim no)
		(in_bom yes)
		(on_board yes)
		(dnp no)
		(property "Reference" "Q6"
			(at 241.935 40.6399 0)
			(effects
				(font
					(size 1.27 1.27)
				)
				(justify left)
			)
		)
		(property "Value" "BSS138PW"
			(at 241.935 43.1799 0)
			(effects
				(font
					(size 1.27 1.27)
					(thickness 0.15)
				)
				(justify left)
			)
		)
		(property "Footprint" "antmicro-footprints:SC70-3"
			(at 254 55.88 0)
			(effects
				(font
					(size 1.27 1.27)
					(thickness 0.15)
				)
				(justify left bottom)
				(hide yes)
			)
		)
		(property "Datasheet" "https://assets.nexperia.com/documents/data-sheet/BSS138PW.pdf"
			(at 254 58.42 0)
			(effects
				(font
					(size 1.27 1.27)
					(thickness 0.15)
				)
				(justify left bottom)
				(hide yes)
			)
		)
		(property "Description" "Power MOSFET, N Channel, 60 V, 320 mA, 0.9 ohm, SOT-323, Surface Mount"
			(at 231.14 44.45 0)
			(effects
				(font
					(size 1.27 1.27)
				)
				(hide yes)
			)
		)
		(property "MPN" "BSS138PW"
			(at 254 60.96 0)
			(effects
				(font
					(size 1.27 1.27)
					(thickness 0.15)
				)
				(justify left bottom)
				(hide yes)
			)
		)
		(property "Manufacturer" "Nexperia"
			(at 254 63.5 0)
			(effects
				(font
					(size 1.27 1.27)
					(thickness 0.15)
				)
				(justify left bottom)
				(hide yes)
			)
		)
		(property "Author" "Antmicro"
			(at 254 66.04 0)
			(effects
				(font
					(size 1.27 1.27)
					(thickness 0.15)
				)
				(justify left bottom)
				(hide yes)
			)
		)
		(property "License" "Apache-2.0"
			(at 254 68.58 0)
			(effects
				(font
					(size 1.27 1.27)
					(thickness 0.15)
				)
				(justify left bottom)
				(hide yes)
			)
		)
		(pin "1"
		)
		(pin "2"
		)
		(pin "3"
		)
		(instances
			(project "artix-dc-scm"
				(path ""
					(reference "Q6")
					(unit 1)
				)
			)
		)
	)
	(symbol
		(lib_id "antmicroWire2BoardConnectors:Molex_Pico-Lock_1x2_504050-0291")
		(at 38.1 120.65 0)
		(mirror y)
		(unit 1)
		(exclude_from_sim no)
		(in_bom yes)
		(on_board yes)
		(dnp no)
		(fields_autoplaced yes)
		(property "Reference" "J10"
			(at 33.02 114.3 0)
			(effects
				(font
					(size 1.27 1.27)
				)
			)
		)
		(property "Value" "Molex_Pico-Lock_1x2_504050-0291"
			(at 29.21 123.19 0)
			(effects
				(font
					(size 1.27 1.27)
					(thickness 0.15)
				)
				(justify left bottom)
				(hide yes)
			)
		)
		(property "Footprint" "antmicro-footprints:Conn_Molex_Pico-Lock_1x2_504050-0291"
			(at 29.21 125.73 0)
			(effects
				(font
					(size 1.27 1.27)
					(thickness 0.15)
				)
				(justify left bottom)
				(hide yes)
			)
		)
		(property "Datasheet" "https://www.molex.com/en-us/products/part-detail-pdf/5040500291?display=pdf"
			(at 29.21 128.27 0)
			(effects
				(font
					(size 1.27 1.27)
					(thickness 0.15)
				)
				(justify left bottom)
				(hide yes)
			)
		)
		(property "Description" "Connector Header Surface Mount, Right Angle 2 position 0.059\" (1.50mm)"
			(at 38.1 120.65 0)
			(effects
				(font
					(size 1.27 1.27)
				)
				(hide yes)
			)
		)
		(property "MPN" "504050-0291"
			(at 33.02 116.84 0)
			(effects
				(font
					(size 1.27 1.27)
					(thickness 0.15)
				)
			)
		)
		(property "Manufacturer" "Molex"
			(at 29.21 130.81 0)
			(effects
				(font
					(size 1.27 1.27)
					(thickness 0.15)
				)
				(justify left bottom)
				(hide yes)
			)
		)
		(property "Author" "Antmicro"
			(at 29.21 135.89 0)
			(effects
				(font
					(size 1.27 1.27)
					(thickness 0.15)
				)
				(justify left bottom)
				(hide yes)
			)
		)
		(property "License" "Apache-2.0"
			(at 29.21 138.43 0)
			(effects
				(font
					(size 1.27 1.27)
					(thickness 0.15)
				)
				(justify left bottom)
				(hide yes)
			)
		)
		(pin "1"
		)
		(pin "2"
		)
		(pin "MP1"
		)
		(pin "MP2"
		)
		(instances
			(project "artix-dc-scm"
				(path ""
					(reference "J10")
					(unit 1)
				)
			)
		)
	)
	(symbol
		(lib_id "antmicropower:GND")
		(at 62.23 208.28 0)
		(unit 1)
		(exclude_from_sim no)
		(in_bom yes)
		(on_board yes)
		(dnp no)
		(property "Reference" "#PWR0157"
			(at 62.23 214.63 0)
			(effects
				(font
					(size 1.27 1.27)
				)
				(hide yes)
			)
		)
		(property "Value" "GND"
			(at 62.23 212.09 0)
			(effects
				(font
					(size 1.27 1.27)
				)
			)
		)
		(property "Footprint" ""
			(at 62.23 208.28 0)
			(effects
				(font
					(size 1.27 1.27)
				)
				(hide yes)
			)
		)
		(property "Datasheet" ""
			(at 62.23 208.28 0)
			(effects
				(font
					(size 1.27 1.27)
				)
				(hide yes)
			)
		)
		(property "Description" ""
			(at 62.23 208.28 0)
			(effects
				(font
					(size 1.27 1.27)
				)
				(hide yes)
			)
		)
		(property "Author" "Antmicro"
			(at 71.12 215.9 0)
			(effects
				(font
					(size 1.27 1.27)
					(thickness 0.15)
				)
				(justify left bottom)
				(hide yes)
			)
		)
		(property "License" "Apache-2.0"
			(at 71.12 218.44 0)
			(effects
				(font
					(size 1.27 1.27)
					(thickness 0.15)
				)
				(justify left bottom)
				(hide yes)
			)
		)
		(pin "1"
		)
		(instances
			(project "artix-dc-scm"
				(path ""
					(reference "#PWR0157")
					(unit 1)
				)
			)
		)
	)
	(symbol
		(lib_id "antmicroTestPoints:TP_1mm_SMD")
		(at 129.54 73.66 0)
		(unit 1)
		(exclude_from_sim no)
		(in_bom no)
		(on_board yes)
		(dnp no)
		(property "Reference" "TP4"
			(at 133.985 73.66 0)
			(effects
				(font
					(size 1.27 1.27)
				)
				(justify left)
			)
		)
		(property "Value" "TP_1mm_SMD"
			(at 129.54 76.2 0)
			(effects
				(font
					(size 1.27 1.27)
				)
				(hide yes)
			)
		)
		(property "Footprint" "antmicro-footprints:TP_SMD_1mm"
			(at 144.78 83.82 0)
			(effects
				(font
					(size 1.27 1.27)
					(thickness 0.15)
				)
				(justify left bottom)
				(hide yes)
			)
		)
		(property "Datasheet" ""
			(at 144.78 86.36 0)
			(effects
				(font
					(size 1.27 1.27)
					(thickness 0.15)
				)
				(justify left bottom)
				(hide yes)
			)
		)
		(property "Description" "Test point 1mm SMD"
			(at 129.54 73.66 0)
			(effects
				(font
					(size 1.27 1.27)
				)
				(hide yes)
			)
		)
		(property "MPN" ""
			(at 129.54 73.66 0)
			(effects
				(font
					(size 1.27 1.27)
				)
				(hide yes)
			)
		)
		(property "Manufacturer" ""
			(at 129.54 73.66 0)
			(effects
				(font
					(size 1.27 1.27)
				)
				(hide yes)
			)
		)
		(property "Author" "Antmicro"
			(at 144.78 88.9 0)
			(effects
				(font
					(size 1.27 1.27)
					(thickness 0.15)
				)
				(justify left bottom)
				(hide yes)
			)
		)
		(property "License" "Apache-2.0"
			(at 144.78 91.44 0)
			(effects
				(font
					(size 1.27 1.27)
					(thickness 0.15)
				)
				(justify left bottom)
				(hide yes)
			)
		)
		(pin "1"
		)
		(instances
			(project "artix-dc-scm"
				(path ""
					(reference "TP4")
					(unit 1)
				)
			)
		)
	)
	(symbol
		(lib_id "antmicroFixedInductors:L_470n_6.7A_Vishay-IHLP-1212AE-11")
		(at 346.71 34.29 0)
		(unit 1)
		(exclude_from_sim no)
		(in_bom yes)
		(on_board yes)
		(dnp no)
		(fields_autoplaced yes)
		(property "Reference" "L2"
			(at 349.25 29.21 0)
			(effects
				(font
					(size 1.27 1.27)
				)
			)
		)
		(property "Value" "L_470n_6.7A_Vishay-IHLP-1212AE-11"
			(at 360.68 36.83 0)
			(effects
				(font
					(size 1.27 1.27)
					(thickness 0.15)
				)
				(justify left bottom)
				(hide yes)
			)
		)
		(property "Footprint" "antmicro-footprints:L_Vishay-IHLP-1212AE"
			(at 360.68 41.91 0)
			(effects
				(font
					(size 1.27 1.27)
					(thickness 0.15)
				)
				(justify left bottom)
				(hide yes)
			)
		)
		(property "Datasheet" "https://www.vishay.com/docs/34300/ihlp-1212ae-11.pdf"
			(at 360.68 44.45 0)
			(effects
				(font
					(size 1.27 1.27)
					(thickness 0.15)
				)
				(justify left bottom)
				(hide yes)
			)
		)
		(property "Description" "Power Inductor (SMT), 470 nH, 6.7 A, Shielded, 6.7 A"
			(at 346.71 34.29 0)
			(effects
				(font
					(size 1.27 1.27)
				)
				(hide yes)
			)
		)
		(property "Manufacturer" "Vishay"
			(at 360.68 46.99 0)
			(effects
				(font
					(size 1.27 1.27)
					(thickness 0.15)
				)
				(justify left bottom)
				(hide yes)
			)
		)
		(property "MPN" "IHLP1212AEERR47M11"
			(at 360.68 49.53 0)
			(effects
				(font
					(size 1.27 1.27)
					(thickness 0.15)
				)
				(justify left bottom)
				(hide yes)
			)
		)
		(property "Val" "470n/6.7A"
			(at 349.25 31.75 0)
			(effects
				(font
					(size 1.27 1.27)
					(thickness 0.15)
				)
			)
		)
		(property "ISat" "6.7 A"
			(at 360.68 50.8 0)
			(effects
				(font
					(size 1.27 1.27)
				)
				(justify left)
				(hide yes)
			)
		)
		(property "IMax" "6.7 A"
			(at 360.68 54.61 0)
			(effects
				(font
					(size 1.27 1.27)
					(thickness 0.15)
				)
				(justify left bottom)
				(hide yes)
			)
		)
		(property "Size" "3.0x3.0"
			(at 360.68 57.15 0)
			(effects
				(font
					(size 1.27 1.27)
					(thickness 0.15)
				)
				(justify left bottom)
				(hide yes)
			)
		)
		(property "Author" "Antmicro"
			(at 360.68 59.69 0)
			(effects
				(font
					(size 1.27 1.27)
					(thickness 0.15)
				)
				(justify left bottom)
				(hide yes)
			)
		)
		(property "License" "Apache-2.0"
			(at 360.68 62.23 0)
			(effects
				(font
					(size 1.27 1.27)
					(thickness 0.15)
				)
				(justify left bottom)
				(hide yes)
			)
		)
		(pin "1"
		)
		(pin "2"
		)
		(instances
			(project "artix-dc-scm"
				(path ""
					(reference "L2")
					(unit 1)
				)
			)
		)
	)
	(symbol
		(lib_id "antmicroFixedInductors:L_470n_6.7A_Vishay-IHLP-1212AE-11")
		(at 346.71 78.74 0)
		(unit 1)
		(exclude_from_sim no)
		(in_bom yes)
		(on_board yes)
		(dnp no)
		(fields_autoplaced yes)
		(property "Reference" "L3"
			(at 349.25 73.025 0)
			(effects
				(font
					(size 1.27 1.27)
				)
			)
		)
		(property "Value" "L_470n_6.7A_Vishay-IHLP-1212AE-11"
			(at 360.68 81.28 0)
			(effects
				(font
					(size 1.27 1.27)
					(thickness 0.15)
				)
				(justify left bottom)
				(hide yes)
			)
		)
		(property "Footprint" "antmicro-footprints:L_Vishay-IHLP-1212AE"
			(at 360.68 86.36 0)
			(effects
				(font
					(size 1.27 1.27)
					(thickness 0.15)
				)
				(justify left bottom)
				(hide yes)
			)
		)
		(property "Datasheet" "https://www.vishay.com/docs/34300/ihlp-1212ae-11.pdf"
			(at 360.68 88.9 0)
			(effects
				(font
					(size 1.27 1.27)
					(thickness 0.15)
				)
				(justify left bottom)
				(hide yes)
			)
		)
		(property "Description" "Power Inductor (SMT), 470 nH, 6.7 A, Shielded, 6.7 A"
			(at 346.71 78.74 0)
			(effects
				(font
					(size 1.27 1.27)
				)
				(hide yes)
			)
		)
		(property "Manufacturer" "Vishay"
			(at 360.68 91.44 0)
			(effects
				(font
					(size 1.27 1.27)
					(thickness 0.15)
				)
				(justify left bottom)
				(hide yes)
			)
		)
		(property "MPN" "IHLP1212AEERR47M11"
			(at 360.68 93.98 0)
			(effects
				(font
					(size 1.27 1.27)
					(thickness 0.15)
				)
				(justify left bottom)
				(hide yes)
			)
		)
		(property "Val" "470n/6.7A"
			(at 349.25 75.565 0)
			(effects
				(font
					(size 1.27 1.27)
					(thickness 0.15)
				)
			)
		)
		(property "ISat" "6.7 A"
			(at 360.68 95.25 0)
			(effects
				(font
					(size 1.27 1.27)
				)
				(justify left)
				(hide yes)
			)
		)
		(property "IMax" "6.7 A"
			(at 360.68 99.06 0)
			(effects
				(font
					(size 1.27 1.27)
					(thickness 0.15)
				)
				(justify left bottom)
				(hide yes)
			)
		)
		(property "Size" "3.0x3.0"
			(at 360.68 101.6 0)
			(effects
				(font
					(size 1.27 1.27)
					(thickness 0.15)
				)
				(justify left bottom)
				(hide yes)
			)
		)
		(property "Author" "Antmicro"
			(at 360.68 104.14 0)
			(effects
				(font
					(size 1.27 1.27)
					(thickness 0.15)
				)
				(justify left bottom)
				(hide yes)
			)
		)
		(property "License" "Apache-2.0"
			(at 360.68 106.68 0)
			(effects
				(font
					(size 1.27 1.27)
					(thickness 0.15)
				)
				(justify left bottom)
				(hide yes)
			)
		)
		(pin "1"
		)
		(pin "2"
		)
		(instances
			(project "artix-dc-scm"
				(path ""
					(reference "L3")
					(unit 1)
				)
			)
		)
	)
	(symbol
		(lib_id "antmicroFixedInductors:L_470n_6.7A_Vishay-IHLP-1212AE-11")
		(at 346.71 123.19 0)
		(unit 1)
		(exclude_from_sim no)
		(in_bom yes)
		(on_board yes)
		(dnp no)
		(fields_autoplaced yes)
		(property "Reference" "L5"
			(at 349.25 118.11 0)
			(effects
				(font
					(size 1.27 1.27)
				)
			)
		)
		(property "Value" "L_470n_6.7A_Vishay-IHLP-1212AE-11"
			(at 360.68 125.73 0)
			(effects
				(font
					(size 1.27 1.27)
					(thickness 0.15)
				)
				(justify left bottom)
				(hide yes)
			)
		)
		(property "Footprint" "antmicro-footprints:L_Vishay-IHLP-1212AE"
			(at 360.68 130.81 0)
			(effects
				(font
					(size 1.27 1.27)
					(thickness 0.15)
				)
				(justify left bottom)
				(hide yes)
			)
		)
		(property "Datasheet" "https://www.vishay.com/docs/34300/ihlp-1212ae-11.pdf"
			(at 360.68 133.35 0)
			(effects
				(font
					(size 1.27 1.27)
					(thickness 0.15)
				)
				(justify left bottom)
				(hide yes)
			)
		)
		(property "Description" "Power Inductor (SMT), 470 nH, 6.7 A, Shielded, 6.7 A"
			(at 346.71 123.19 0)
			(effects
				(font
					(size 1.27 1.27)
				)
				(hide yes)
			)
		)
		(property "Manufacturer" "Vishay"
			(at 360.68 135.89 0)
			(effects
				(font
					(size 1.27 1.27)
					(thickness 0.15)
				)
				(justify left bottom)
				(hide yes)
			)
		)
		(property "MPN" "IHLP1212AEERR47M11"
			(at 360.68 138.43 0)
			(effects
				(font
					(size 1.27 1.27)
					(thickness 0.15)
				)
				(justify left bottom)
				(hide yes)
			)
		)
		(property "Val" "470n/6.7A"
			(at 349.25 120.65 0)
			(effects
				(font
					(size 1.27 1.27)
					(thickness 0.15)
				)
			)
		)
		(property "ISat" "6.7 A"
			(at 360.68 139.7 0)
			(effects
				(font
					(size 1.27 1.27)
				)
				(justify left)
				(hide yes)
			)
		)
		(property "IMax" "6.7 A"
			(at 360.68 143.51 0)
			(effects
				(font
					(size 1.27 1.27)
					(thickness 0.15)
				)
				(justify left bottom)
				(hide yes)
			)
		)
		(property "Size" "3.0x3.0"
			(at 360.68 146.05 0)
			(effects
				(font
					(size 1.27 1.27)
					(thickness 0.15)
				)
				(justify left bottom)
				(hide yes)
			)
		)
		(property "Author" "Antmicro"
			(at 360.68 148.59 0)
			(effects
				(font
					(size 1.27 1.27)
					(thickness 0.15)
				)
				(justify left bottom)
				(hide yes)
			)
		)
		(property "License" "Apache-2.0"
			(at 360.68 151.13 0)
			(effects
				(font
					(size 1.27 1.27)
					(thickness 0.15)
				)
				(justify left bottom)
				(hide yes)
			)
		)
		(pin "1"
		)
		(pin "2"
		)
		(instances
			(project "artix-dc-scm"
				(path ""
					(reference "L5")
					(unit 1)
				)
			)
		)
	)
	(symbol
		(lib_id "antmicroFixedInductors:L_470n_6.7A_Vishay-IHLP-1212AE-11")
		(at 346.71 167.64 0)
		(unit 1)
		(exclude_from_sim no)
		(in_bom yes)
		(on_board yes)
		(dnp no)
		(fields_autoplaced yes)
		(property "Reference" "L4"
			(at 349.25 161.925 0)
			(effects
				(font
					(size 1.27 1.27)
				)
			)
		)
		(property "Value" "L_470n_6.7A_Vishay-IHLP-1212AE-11"
			(at 360.68 170.18 0)
			(effects
				(font
					(size 1.27 1.27)
					(thickness 0.15)
				)
				(justify left bottom)
				(hide yes)
			)
		)
		(property "Footprint" "antmicro-footprints:L_Vishay-IHLP-1212AE"
			(at 360.68 175.26 0)
			(effects
				(font
					(size 1.27 1.27)
					(thickness 0.15)
				)
				(justify left bottom)
				(hide yes)
			)
		)
		(property "Datasheet" "https://www.vishay.com/docs/34300/ihlp-1212ae-11.pdf"
			(at 360.68 177.8 0)
			(effects
				(font
					(size 1.27 1.27)
					(thickness 0.15)
				)
				(justify left bottom)
				(hide yes)
			)
		)
		(property "Description" "Power Inductor (SMT), 470 nH, 6.7 A, Shielded, 6.7 A"
			(at 346.71 167.64 0)
			(effects
				(font
					(size 1.27 1.27)
				)
				(hide yes)
			)
		)
		(property "Manufacturer" "Vishay"
			(at 360.68 180.34 0)
			(effects
				(font
					(size 1.27 1.27)
					(thickness 0.15)
				)
				(justify left bottom)
				(hide yes)
			)
		)
		(property "MPN" "IHLP1212AEERR47M11"
			(at 360.68 182.88 0)
			(effects
				(font
					(size 1.27 1.27)
					(thickness 0.15)
				)
				(justify left bottom)
				(hide yes)
			)
		)
		(property "Val" "470n/6.7A"
			(at 349.25 164.465 0)
			(effects
				(font
					(size 1.27 1.27)
					(thickness 0.15)
				)
			)
		)
		(property "ISat" "6.7 A"
			(at 360.68 184.15 0)
			(effects
				(font
					(size 1.27 1.27)
				)
				(justify left)
				(hide yes)
			)
		)
		(property "IMax" "6.7 A"
			(at 360.68 187.96 0)
			(effects
				(font
					(size 1.27 1.27)
					(thickness 0.15)
				)
				(justify left bottom)
				(hide yes)
			)
		)
		(property "Size" "3.0x3.0"
			(at 360.68 190.5 0)
			(effects
				(font
					(size 1.27 1.27)
					(thickness 0.15)
				)
				(justify left bottom)
				(hide yes)
			)
		)
		(property "Author" "Antmicro"
			(at 360.68 193.04 0)
			(effects
				(font
					(size 1.27 1.27)
					(thickness 0.15)
				)
				(justify left bottom)
				(hide yes)
			)
		)
		(property "License" "Apache-2.0"
			(at 360.68 195.58 0)
			(effects
				(font
					(size 1.27 1.27)
					(thickness 0.15)
				)
				(justify left bottom)
				(hide yes)
			)
		)
		(pin "1"
		)
		(pin "2"
		)
		(instances
			(project "artix-dc-scm"
				(path ""
					(reference "L4")
					(unit 1)
				)
			)
		)
	)
	(symbol
		(lib_id "antmicroResistors0603:R_0R_0603")
		(at 388.62 34.29 180)
		(unit 1)
		(exclude_from_sim no)
		(in_bom yes)
		(on_board yes)
		(dnp no)
		(property "Reference" "R139"
			(at 386.08 31.75 0)
			(effects
				(font
					(size 1.27 1.27)
				)
			)
		)
		(property "Value" "R_0R_0603"
			(at 368.3 21.59 0)
			(effects
				(font
					(size 1.27 1.27)
					(thickness 0.15)
				)
				(justify left bottom)
				(hide yes)
			)
		)
		(property "Footprint" "antmicro-footprints:R_0603_1608Metric"
			(at 368.3 19.05 0)
			(effects
				(font
					(size 1.27 1.27)
					(thickness 0.15)
				)
				(justify left bottom)
				(hide yes)
			)
		)
		(property "Datasheet" "https://www.bourns.com/docs/product-datasheets/cr.pdf?sfvrsn=574d41f6_14"
			(at 368.3 16.51 0)
			(effects
				(font
					(size 1.27 1.27)
					(thickness 0.15)
				)
				(justify left bottom)
				(hide yes)
			)
		)
		(property "Description" "Zero Ohm Resistor, Jumper, 0603 [1608 Metric], Thick Film, 100 mW, 1 A, Surface Mount Device, CR"
			(at 388.62 34.29 0)
			(effects
				(font
					(size 1.27 1.27)
				)
				(hide yes)
			)
		)
		(property "Manufacturer" "Bourns"
			(at 368.3 11.43 0)
			(effects
				(font
					(size 1.27 1.27)
					(thickness 0.15)
				)
				(justify left bottom)
				(hide yes)
			)
		)
		(property "MPN" "CR0603-J/-000ELF"
			(at 368.3 13.97 0)
			(effects
				(font
					(size 1.27 1.27)
					(thickness 0.15)
				)
				(justify left bottom)
				(hide yes)
			)
		)
		(property "Val" "0R"
			(at 386.08 36.83 0)
			(effects
				(font
					(size 1.27 1.27)
					(thickness 0.15)
				)
			)
		)
		(property "License" "Apache-2.0"
			(at 368.3 8.89 0)
			(effects
				(font
					(size 1.27 1.27)
					(thickness 0.15)
				)
				(justify left bottom)
				(hide yes)
			)
		)
		(property "Author" "Antmicro"
			(at 368.3 6.35 0)
			(effects
				(font
					(size 1.27 1.27)
					(thickness 0.15)
				)
				(justify left bottom)
				(hide yes)
			)
		)
		(property "Tolerance" "~"
			(at 368.3 24.13 0)
			(effects
				(font
					(size 1.27 1.27)
				)
				(justify left bottom)
				(hide yes)
			)
		)
		(property "Current" "1A"
			(at 383.5401 36.195 90)
			(effects
				(font
					(size 1.27 1.27)
					(thickness 0.15)
				)
				(justify left)
				(hide yes)
			)
		)
		(pin "1"
		)
		(pin "2"
		)
		(instances
			(project "artix-dc-scm"
				(path ""
					(reference "R139")
					(unit 1)
				)
			)
		)
	)
	(symbol
		(lib_id "antmicroResistors0603:R_0R_0603")
		(at 388.62 78.74 180)
		(unit 1)
		(exclude_from_sim no)
		(in_bom yes)
		(on_board yes)
		(dnp no)
		(property "Reference" "R140"
			(at 386.08 76.2 0)
			(effects
				(font
					(size 1.27 1.27)
				)
			)
		)
		(property "Value" "R_0R_0603"
			(at 368.3 66.04 0)
			(effects
				(font
					(size 1.27 1.27)
					(thickness 0.15)
				)
				(justify left bottom)
				(hide yes)
			)
		)
		(property "Footprint" "antmicro-footprints:R_0603_1608Metric"
			(at 368.3 63.5 0)
			(effects
				(font
					(size 1.27 1.27)
					(thickness 0.15)
				)
				(justify left bottom)
				(hide yes)
			)
		)
		(property "Datasheet" "https://www.bourns.com/docs/product-datasheets/cr.pdf?sfvrsn=574d41f6_14"
			(at 368.3 60.96 0)
			(effects
				(font
					(size 1.27 1.27)
					(thickness 0.15)
				)
				(justify left bottom)
				(hide yes)
			)
		)
		(property "Description" "Zero Ohm Resistor, Jumper, 0603 [1608 Metric], Thick Film, 100 mW, 1 A, Surface Mount Device, CR"
			(at 388.62 78.74 0)
			(effects
				(font
					(size 1.27 1.27)
				)
				(hide yes)
			)
		)
		(property "Manufacturer" "Bourns"
			(at 368.3 55.88 0)
			(effects
				(font
					(size 1.27 1.27)
					(thickness 0.15)
				)
				(justify left bottom)
				(hide yes)
			)
		)
		(property "MPN" "CR0603-J/-000ELF"
			(at 368.3 58.42 0)
			(effects
				(font
					(size 1.27 1.27)
					(thickness 0.15)
				)
				(justify left bottom)
				(hide yes)
			)
		)
		(property "Val" "0R"
			(at 386.08 81.28 0)
			(effects
				(font
					(size 1.27 1.27)
					(thickness 0.15)
				)
			)
		)
		(property "License" "Apache-2.0"
			(at 368.3 53.34 0)
			(effects
				(font
					(size 1.27 1.27)
					(thickness 0.15)
				)
				(justify left bottom)
				(hide yes)
			)
		)
		(property "Author" "Antmicro"
			(at 368.3 50.8 0)
			(effects
				(font
					(size 1.27 1.27)
					(thickness 0.15)
				)
				(justify left bottom)
				(hide yes)
			)
		)
		(property "Tolerance" "~"
			(at 368.3 68.58 0)
			(effects
				(font
					(size 1.27 1.27)
				)
				(justify left bottom)
				(hide yes)
			)
		)
		(property "Current" "1A"
			(at 386.08 74.93 0)
			(effects
				(font
					(size 1.27 1.27)
					(thickness 0.15)
				)
				(hide yes)
			)
		)
		(pin "1"
		)
		(pin "2"
		)
		(instances
			(project "artix-dc-scm"
				(path ""
					(reference "R140")
					(unit 1)
				)
			)
		)
	)
	(symbol
		(lib_id "antmicroResistors0603:R_0R_0603")
		(at 388.62 123.19 180)
		(unit 1)
		(exclude_from_sim no)
		(in_bom yes)
		(on_board yes)
		(dnp no)
		(property "Reference" "R142"
			(at 386.08 120.65 0)
			(effects
				(font
					(size 1.27 1.27)
				)
			)
		)
		(property "Value" "R_0R_0603"
			(at 368.3 110.49 0)
			(effects
				(font
					(size 1.27 1.27)
					(thickness 0.15)
				)
				(justify left bottom)
				(hide yes)
			)
		)
		(property "Footprint" "antmicro-footprints:R_0603_1608Metric"
			(at 368.3 107.95 0)
			(effects
				(font
					(size 1.27 1.27)
					(thickness 0.15)
				)
				(justify left bottom)
				(hide yes)
			)
		)
		(property "Datasheet" "https://www.bourns.com/docs/product-datasheets/cr.pdf?sfvrsn=574d41f6_14"
			(at 368.3 105.41 0)
			(effects
				(font
					(size 1.27 1.27)
					(thickness 0.15)
				)
				(justify left bottom)
				(hide yes)
			)
		)
		(property "Description" "Zero Ohm Resistor, Jumper, 0603 [1608 Metric], Thick Film, 100 mW, 1 A, Surface Mount Device, CR"
			(at 388.62 123.19 0)
			(effects
				(font
					(size 1.27 1.27)
				)
				(hide yes)
			)
		)
		(property "Manufacturer" "Bourns"
			(at 368.3 100.33 0)
			(effects
				(font
					(size 1.27 1.27)
					(thickness 0.15)
				)
				(justify left bottom)
				(hide yes)
			)
		)
		(property "MPN" "CR0603-J/-000ELF"
			(at 368.3 102.87 0)
			(effects
				(font
					(size 1.27 1.27)
					(thickness 0.15)
				)
				(justify left bottom)
				(hide yes)
			)
		)
		(property "Val" "0R"
			(at 386.08 125.73 0)
			(effects
				(font
					(size 1.27 1.27)
					(thickness 0.15)
				)
			)
		)
		(property "License" "Apache-2.0"
			(at 368.3 97.79 0)
			(effects
				(font
					(size 1.27 1.27)
					(thickness 0.15)
				)
				(justify left bottom)
				(hide yes)
			)
		)
		(property "Author" "Antmicro"
			(at 368.3 95.25 0)
			(effects
				(font
					(size 1.27 1.27)
					(thickness 0.15)
				)
				(justify left bottom)
				(hide yes)
			)
		)
		(property "Tolerance" "~"
			(at 368.3 113.03 0)
			(effects
				(font
					(size 1.27 1.27)
				)
				(justify left bottom)
				(hide yes)
			)
		)
		(property "Current" "1A"
			(at 386.08 132.08 0)
			(effects
				(font
					(size 1.27 1.27)
					(thickness 0.15)
				)
				(hide yes)
			)
		)
		(pin "1"
		)
		(pin "2"
		)
		(instances
			(project "artix-dc-scm"
				(path ""
					(reference "R142")
					(unit 1)
				)
			)
		)
	)
	(symbol
		(lib_id "antmicroResistors0603:R_0R_0603")
		(at 388.62 167.64 180)
		(unit 1)
		(exclude_from_sim no)
		(in_bom yes)
		(on_board yes)
		(dnp no)
		(property "Reference" "R141"
			(at 386.08 165.1 0)
			(effects
				(font
					(size 1.27 1.27)
				)
			)
		)
		(property "Value" "R_0R_0603"
			(at 368.3 154.94 0)
			(effects
				(font
					(size 1.27 1.27)
					(thickness 0.15)
				)
				(justify left bottom)
				(hide yes)
			)
		)
		(property "Footprint" "antmicro-footprints:R_0603_1608Metric"
			(at 368.3 152.4 0)
			(effects
				(font
					(size 1.27 1.27)
					(thickness 0.15)
				)
				(justify left bottom)
				(hide yes)
			)
		)
		(property "Datasheet" "https://www.bourns.com/docs/product-datasheets/cr.pdf?sfvrsn=574d41f6_14"
			(at 368.3 149.86 0)
			(effects
				(font
					(size 1.27 1.27)
					(thickness 0.15)
				)
				(justify left bottom)
				(hide yes)
			)
		)
		(property "Description" "Zero Ohm Resistor, Jumper, 0603 [1608 Metric], Thick Film, 100 mW, 1 A, Surface Mount Device, CR"
			(at 388.62 167.64 0)
			(effects
				(font
					(size 1.27 1.27)
				)
				(hide yes)
			)
		)
		(property "Manufacturer" "Bourns"
			(at 368.3 144.78 0)
			(effects
				(font
					(size 1.27 1.27)
					(thickness 0.15)
				)
				(justify left bottom)
				(hide yes)
			)
		)
		(property "MPN" "CR0603-J/-000ELF"
			(at 368.3 147.32 0)
			(effects
				(font
					(size 1.27 1.27)
					(thickness 0.15)
				)
				(justify left bottom)
				(hide yes)
			)
		)
		(property "Val" "0R"
			(at 386.08 170.18 0)
			(effects
				(font
					(size 1.27 1.27)
					(thickness 0.15)
				)
			)
		)
		(property "License" "Apache-2.0"
			(at 368.3 142.24 0)
			(effects
				(font
					(size 1.27 1.27)
					(thickness 0.15)
				)
				(justify left bottom)
				(hide yes)
			)
		)
		(property "Author" "Antmicro"
			(at 368.3 139.7 0)
			(effects
				(font
					(size 1.27 1.27)
					(thickness 0.15)
				)
				(justify left bottom)
				(hide yes)
			)
		)
		(property "Tolerance" "~"
			(at 368.3 157.48 0)
			(effects
				(font
					(size 1.27 1.27)
				)
				(justify left bottom)
				(hide yes)
			)
		)
		(property "Current" "1A"
			(at 386.08 164.465 0)
			(effects
				(font
					(size 1.27 1.27)
					(thickness 0.15)
				)
				(hide yes)
			)
		)
		(pin "1"
		)
		(pin "2"
		)
		(instances
			(project "artix-dc-scm"
				(path ""
					(reference "R141")
					(unit 1)
				)
			)
		)
	)
	(symbol
		(lib_id "antmicroTransistorsFETsMOSFETsSingle:BSS138PW")
		(at 229.87 104.14 0)
		(unit 1)
		(exclude_from_sim no)
		(in_bom yes)
		(on_board yes)
		(dnp no)
		(property "Reference" "Q3"
			(at 240.665 100.3299 0)
			(effects
				(font
					(size 1.27 1.27)
				)
				(justify left)
			)
		)
		(property "Value" "BSS138PW"
			(at 240.665 102.8699 0)
			(effects
				(font
					(size 1.27 1.27)
					(thickness 0.15)
				)
				(justify left)
			)
		)
		(property "Footprint" "antmicro-footprints:SC70-3"
			(at 252.73 115.57 0)
			(effects
				(font
					(size 1.27 1.27)
					(thickness 0.15)
				)
				(justify left bottom)
				(hide yes)
			)
		)
		(property "Datasheet" "https://assets.nexperia.com/documents/data-sheet/BSS138PW.pdf"
			(at 252.73 118.11 0)
			(effects
				(font
					(size 1.27 1.27)
					(thickness 0.15)
				)
				(justify left bottom)
				(hide yes)
			)
		)
		(property "Description" "Power MOSFET, N Channel, 60 V, 320 mA, 0.9 ohm, SOT-323, Surface Mount"
			(at 229.87 104.14 0)
			(effects
				(font
					(size 1.27 1.27)
				)
				(hide yes)
			)
		)
		(property "MPN" "BSS138PW"
			(at 252.73 120.65 0)
			(effects
				(font
					(size 1.27 1.27)
					(thickness 0.15)
				)
				(justify left bottom)
				(hide yes)
			)
		)
		(property "Manufacturer" "Nexperia"
			(at 252.73 123.19 0)
			(effects
				(font
					(size 1.27 1.27)
					(thickness 0.15)
				)
				(justify left bottom)
				(hide yes)
			)
		)
		(property "Author" "Antmicro"
			(at 252.73 125.73 0)
			(effects
				(font
					(size 1.27 1.27)
					(thickness 0.15)
				)
				(justify left bottom)
				(hide yes)
			)
		)
		(property "License" "Apache-2.0"
			(at 252.73 128.27 0)
			(effects
				(font
					(size 1.27 1.27)
					(thickness 0.15)
				)
				(justify left bottom)
				(hide yes)
			)
		)
		(pin "1"
		)
		(pin "2"
		)
		(pin "3"
		)
		(instances
			(project "artix-dc-scm"
				(path ""
					(reference "Q3")
					(unit 1)
				)
			)
		)
	)
	(symbol
		(lib_id "antmicroTransistorsFETsMOSFETsSingle:BSS138PW")
		(at 229.87 134.62 0)
		(unit 1)
		(exclude_from_sim no)
		(in_bom yes)
		(on_board yes)
		(dnp no)
		(property "Reference" "Q4"
			(at 241.3 130.8099 0)
			(effects
				(font
					(size 1.27 1.27)
				)
				(justify left)
			)
		)
		(property "Value" "BSS138PW"
			(at 241.3 133.3499 0)
			(effects
				(font
					(size 1.27 1.27)
					(thickness 0.15)
				)
				(justify left)
			)
		)
		(property "Footprint" "antmicro-footprints:SC70-3"
			(at 252.73 146.05 0)
			(effects
				(font
					(size 1.27 1.27)
					(thickness 0.15)
				)
				(justify left bottom)
				(hide yes)
			)
		)
		(property "Datasheet" "https://assets.nexperia.com/documents/data-sheet/BSS138PW.pdf"
			(at 252.73 148.59 0)
			(effects
				(font
					(size 1.27 1.27)
					(thickness 0.15)
				)
				(justify left bottom)
				(hide yes)
			)
		)
		(property "Description" "Power MOSFET, N Channel, 60 V, 320 mA, 0.9 ohm, SOT-323, Surface Mount"
			(at 229.87 134.62 0)
			(effects
				(font
					(size 1.27 1.27)
				)
				(hide yes)
			)
		)
		(property "MPN" "BSS138PW"
			(at 252.73 151.13 0)
			(effects
				(font
					(size 1.27 1.27)
					(thickness 0.15)
				)
				(justify left bottom)
				(hide yes)
			)
		)
		(property "Manufacturer" "Nexperia"
			(at 252.73 153.67 0)
			(effects
				(font
					(size 1.27 1.27)
					(thickness 0.15)
				)
				(justify left bottom)
				(hide yes)
			)
		)
		(property "Author" "Antmicro"
			(at 252.73 156.21 0)
			(effects
				(font
					(size 1.27 1.27)
					(thickness 0.15)
				)
				(justify left bottom)
				(hide yes)
			)
		)
		(property "License" "Apache-2.0"
			(at 252.73 158.75 0)
			(effects
				(font
					(size 1.27 1.27)
					(thickness 0.15)
				)
				(justify left bottom)
				(hide yes)
			)
		)
		(pin "1"
		)
		(pin "2"
		)
		(pin "3"
		)
		(instances
			(project "artix-dc-scm"
				(path ""
					(reference "Q4")
					(unit 1)
				)
			)
		)
	)
	(symbol
		(lib_id "antmicroTransistorsFETsMOSFETsSingle:BSS138PW")
		(at 228.6 167.64 0)
		(unit 1)
		(exclude_from_sim no)
		(in_bom yes)
		(on_board yes)
		(dnp no)
		(property "Reference" "Q1"
			(at 240.03 163.8299 0)
			(effects
				(font
					(size 1.27 1.27)
				)
				(justify left)
			)
		)
		(property "Value" "BSS138PW"
			(at 240.03 166.3699 0)
			(effects
				(font
					(size 1.27 1.27)
					(thickness 0.15)
				)
				(justify left)
			)
		)
		(property "Footprint" "antmicro-footprints:SC70-3"
			(at 251.46 179.07 0)
			(effects
				(font
					(size 1.27 1.27)
					(thickness 0.15)
				)
				(justify left bottom)
				(hide yes)
			)
		)
		(property "Datasheet" "https://assets.nexperia.com/documents/data-sheet/BSS138PW.pdf"
			(at 251.46 181.61 0)
			(effects
				(font
					(size 1.27 1.27)
					(thickness 0.15)
				)
				(justify left bottom)
				(hide yes)
			)
		)
		(property "Description" "Power MOSFET, N Channel, 60 V, 320 mA, 0.9 ohm, SOT-323, Surface Mount"
			(at 228.6 167.64 0)
			(effects
				(font
					(size 1.27 1.27)
				)
				(hide yes)
			)
		)
		(property "MPN" "BSS138PW"
			(at 251.46 184.15 0)
			(effects
				(font
					(size 1.27 1.27)
					(thickness 0.15)
				)
				(justify left bottom)
				(hide yes)
			)
		)
		(property "Manufacturer" "Nexperia"
			(at 251.46 186.69 0)
			(effects
				(font
					(size 1.27 1.27)
					(thickness 0.15)
				)
				(justify left bottom)
				(hide yes)
			)
		)
		(property "Author" "Antmicro"
			(at 251.46 189.23 0)
			(effects
				(font
					(size 1.27 1.27)
					(thickness 0.15)
				)
				(justify left bottom)
				(hide yes)
			)
		)
		(property "License" "Apache-2.0"
			(at 251.46 191.77 0)
			(effects
				(font
					(size 1.27 1.27)
					(thickness 0.15)
				)
				(justify left bottom)
				(hide yes)
			)
		)
		(pin "1"
		)
		(pin "2"
		)
		(pin "3"
		)
		(instances
			(project "artix-dc-scm"
				(path ""
					(reference "Q1")
					(unit 1)
				)
			)
		)
	)
	(symbol
		(lib_id "antmicroTransistorsFETsMOSFETsSingle:BSS138PW")
		(at 228.6 198.12 0)
		(unit 1)
		(exclude_from_sim no)
		(in_bom yes)
		(on_board yes)
		(dnp no)
		(property "Reference" "Q2"
			(at 240.03 194.3099 0)
			(effects
				(font
					(size 1.27 1.27)
				)
				(justify left)
			)
		)
		(property "Value" "BSS138PW"
			(at 240.03 196.8499 0)
			(effects
				(font
					(size 1.27 1.27)
					(thickness 0.15)
				)
				(justify left)
			)
		)
		(property "Footprint" "antmicro-footprints:SC70-3"
			(at 251.46 209.55 0)
			(effects
				(font
					(size 1.27 1.27)
					(thickness 0.15)
				)
				(justify left bottom)
				(hide yes)
			)
		)
		(property "Datasheet" "https://assets.nexperia.com/documents/data-sheet/BSS138PW.pdf"
			(at 251.46 212.09 0)
			(effects
				(font
					(size 1.27 1.27)
					(thickness 0.15)
				)
				(justify left bottom)
				(hide yes)
			)
		)
		(property "Description" "Power MOSFET, N Channel, 60 V, 320 mA, 0.9 ohm, SOT-323, Surface Mount"
			(at 228.6 198.12 0)
			(effects
				(font
					(size 1.27 1.27)
				)
				(hide yes)
			)
		)
		(property "MPN" "BSS138PW"
			(at 251.46 214.63 0)
			(effects
				(font
					(size 1.27 1.27)
					(thickness 0.15)
				)
				(justify left bottom)
				(hide yes)
			)
		)
		(property "Manufacturer" "Nexperia"
			(at 251.46 217.17 0)
			(effects
				(font
					(size 1.27 1.27)
					(thickness 0.15)
				)
				(justify left bottom)
				(hide yes)
			)
		)
		(property "Author" "Antmicro"
			(at 251.46 219.71 0)
			(effects
				(font
					(size 1.27 1.27)
					(thickness 0.15)
				)
				(justify left bottom)
				(hide yes)
			)
		)
		(property "License" "Apache-2.0"
			(at 251.46 222.25 0)
			(effects
				(font
					(size 1.27 1.27)
					(thickness 0.15)
				)
				(justify left bottom)
				(hide yes)
			)
		)
		(pin "1"
		)
		(pin "2"
		)
		(pin "3"
		)
		(instances
			(project "artix-dc-scm"
				(path ""
					(reference "Q2")
					(unit 1)
				)
			)
		)
	)
	(symbol
		(lib_id "antmicroTransistorsFETsMOSFETsSingle:BSS138PW")
		(at 231.14 72.39 0)
		(unit 1)
		(exclude_from_sim no)
		(in_bom yes)
		(on_board yes)
		(dnp no)
		(property "Reference" "Q5"
			(at 241.935 68.5799 0)
			(effects
				(font
					(size 1.27 1.27)
				)
				(justify left)
			)
		)
		(property "Value" "BSS138PW"
			(at 241.935 71.1199 0)
			(effects
				(font
					(size 1.27 1.27)
					(thickness 0.15)
				)
				(justify left)
			)
		)
		(property "Footprint" "antmicro-footprints:SC70-3"
			(at 254 83.82 0)
			(effects
				(font
					(size 1.27 1.27)
					(thickness 0.15)
				)
				(justify left bottom)
				(hide yes)
			)
		)
		(property "Datasheet" "https://assets.nexperia.com/documents/data-sheet/BSS138PW.pdf"
			(at 254 86.36 0)
			(effects
				(font
					(size 1.27 1.27)
					(thickness 0.15)
				)
				(justify left bottom)
				(hide yes)
			)
		)
		(property "Description" "Power MOSFET, N Channel, 60 V, 320 mA, 0.9 ohm, SOT-323, Surface Mount"
			(at 231.14 72.39 0)
			(effects
				(font
					(size 1.27 1.27)
				)
				(hide yes)
			)
		)
		(property "MPN" "BSS138PW"
			(at 254 88.9 0)
			(effects
				(font
					(size 1.27 1.27)
					(thickness 0.15)
				)
				(justify left bottom)
				(hide yes)
			)
		)
		(property "Manufacturer" "Nexperia"
			(at 254 91.44 0)
			(effects
				(font
					(size 1.27 1.27)
					(thickness 0.15)
				)
				(justify left bottom)
				(hide yes)
			)
		)
		(property "Author" "Antmicro"
			(at 254 93.98 0)
			(effects
				(font
					(size 1.27 1.27)
					(thickness 0.15)
				)
				(justify left bottom)
				(hide yes)
			)
		)
		(property "License" "Apache-2.0"
			(at 254 96.52 0)
			(effects
				(font
					(size 1.27 1.27)
					(thickness 0.15)
				)
				(justify left bottom)
				(hide yes)
			)
		)
		(pin "1"
		)
		(pin "2"
		)
		(pin "3"
		)
		(instances
			(project "artix-dc-scm"
				(path ""
					(reference "Q5")
					(unit 1)
				)
			)
		)
	)
	(symbol
		(lib_id "antmicroPMICVoltageRegulatorsLinear:TPS54561QDPRRQ1")
		(at 95.25 73.66 0)
		(unit 1)
		(exclude_from_sim no)
		(in_bom yes)
		(on_board yes)
		(dnp no)
		(fields_autoplaced yes)
		(property "Reference" "U25"
			(at 107.95 66.675 0)
			(effects
				(font
					(size 1.27 1.27)
				)
			)
		)
		(property "Value" "TPS54561QDPRRQ1"
			(at 107.95 69.215 0)
			(effects
				(font
					(size 1.27 1.27)
					(thickness 0.15)
				)
			)
		)
		(property "Footprint" "antmicro-footprints:WSON-10-1EP_4x4mm_P0.8mm_EP2.6x3mm"
			(at 133.35 81.28 0)
			(effects
				(font
					(size 1.27 1.27)
					(thickness 0.15)
				)
				(justify left bottom)
				(hide yes)
			)
		)
		(property "Datasheet" "https://www.ti.com/lit/ds/symlink/tps54561-q1.pdf?ts=1678720110394&ref_url=https%253A%252F%252Fwww.google.com%252F"
			(at 133.35 83.82 0)
			(effects
				(font
					(size 1.27 1.27)
					(thickness 0.15)
				)
				(justify left bottom)
				(hide yes)
			)
		)
		(property "Description" "DC/DC converter"
			(at 95.25 73.66 0)
			(effects
				(font
					(size 1.27 1.27)
				)
				(hide yes)
			)
		)
		(property "Manufacturer" "Texas Instruments"
			(at 133.35 86.36 0)
			(effects
				(font
					(size 1.27 1.27)
					(thickness 0.15)
				)
				(justify left bottom)
				(hide yes)
			)
		)
		(property "MPN" "TPS54561QDPRRQ1"
			(at 133.35 88.9 0)
			(effects
				(font
					(size 1.27 1.27)
					(thickness 0.15)
				)
				(justify left bottom)
				(hide yes)
			)
		)
		(property "Author" "Antmicro"
			(at 133.35 91.44 0)
			(effects
				(font
					(size 1.27 1.27)
					(thickness 0.15)
				)
				(justify left bottom)
				(hide yes)
			)
		)
		(property "License" "Apache-2.0"
			(at 133.35 93.98 0)
			(effects
				(font
					(size 1.27 1.27)
					(thickness 0.15)
				)
				(justify left bottom)
				(hide yes)
			)
		)
		(pin "1"
		)
		(pin "10"
		)
		(pin "11"
		)
		(pin "2"
		)
		(pin "3"
		)
		(pin "4"
		)
		(pin "5"
		)
		(pin "6"
		)
		(pin "7"
		)
		(pin "8"
		)
		(pin "9"
		)
		(instances
			(project "artix-dc-scm"
				(path ""
					(reference "U25")
					(unit 1)
				)
			)
		)
	)
	(symbol
		(lib_id "antmicroCapacitorsmisc:C_2u2_0603_25V")
		(at 74.93 63.5 90)
		(unit 1)
		(exclude_from_sim no)
		(in_bom yes)
		(on_board yes)
		(dnp no)
		(property "Reference" "C65"
			(at 75.565 59.055 90)
			(effects
				(font
					(size 1.27 1.27)
				)
				(justify right)
			)
		)
		(property "Value" "C_2u2_0603_25V"
			(at 85.09 43.18 0)
			(effects
				(font
					(size 1.27 1.27)
					(thickness 0.15)
				)
				(justify left bottom)
				(hide yes)
			)
		)
		(property "Footprint" "antmicro-footprints:C_0603_1608Metric"
			(at 87.63 43.18 0)
			(effects
				(font
					(size 1.27 1.27)
					(thickness 0.15)
				)
				(justify left bottom)
				(hide yes)
			)
		)
		(property "Datasheet" "https://www.murata.com/products/productdetail?partno=GRM188R61E225KA12%23"
			(at 90.17 43.18 0)
			(effects
				(font
					(size 1.27 1.27)
					(thickness 0.15)
				)
				(justify left bottom)
				(hide yes)
			)
		)
		(property "Description" "SMD Multilayer Ceramic Capacitor, 2.2 µF, 25 V, 0603 [1608 Metric], ± 10%, X5R, GRM Series"
			(at 74.93 63.5 0)
			(effects
				(font
					(size 1.27 1.27)
				)
				(hide yes)
			)
		)
		(property "Manufacturer" "Murata"
			(at 95.25 43.18 0)
			(effects
				(font
					(size 1.27 1.27)
					(thickness 0.15)
				)
				(justify left bottom)
				(hide yes)
			)
		)
		(property "MPN" "GRM188R61E225KA12D"
			(at 92.71 43.18 0)
			(effects
				(font
					(size 1.27 1.27)
					(thickness 0.15)
				)
				(justify left bottom)
				(hide yes)
			)
		)
		(property "Val" "2u2"
			(at 75.565 62.865 90)
			(effects
				(font
					(size 1.27 1.27)
					(thickness 0.15)
				)
				(justify right)
			)
		)
		(property "License" "Apache-2.0"
			(at 97.79 43.18 0)
			(effects
				(font
					(size 1.27 1.27)
					(thickness 0.15)
				)
				(justify left bottom)
				(hide yes)
			)
		)
		(property "Author" "Antmicro"
			(at 100.33 43.18 0)
			(effects
				(font
					(size 1.27 1.27)
					(thickness 0.15)
				)
				(justify left bottom)
				(hide yes)
			)
		)
		(property "Voltage" ""
			(at 102.87 43.18 0)
			(effects
				(font
					(size 1.27 1.27)
				)
				(justify left bottom)
				(hide yes)
			)
		)
		(property "Dielectric" ""
			(at 105.41 43.18 0)
			(effects
				(font
					(size 1.27 1.27)
				)
				(justify left bottom)
				(hide yes)
			)
		)
		(property "Public" "False"
			(at 107.95 43.18 0)
			(effects
				(font
					(size 1.27 1.27)
				)
				(justify left bottom)
				(hide yes)
			)
		)
		(pin "1"
		)
		(pin "2"
		)
		(instances
			(project "artix-dc-scm"
				(path ""
					(reference "C65")
					(unit 1)
				)
			)
		)
	)
	(symbol
		(lib_id "antmicroCapacitorsmisc:C_2u2_0603_25V")
		(at 81.28 63.5 90)
		(unit 1)
		(exclude_from_sim no)
		(in_bom yes)
		(on_board yes)
		(dnp no)
		(property "Reference" "C66"
			(at 81.915 59.055 90)
			(effects
				(font
					(size 1.27 1.27)
				)
				(justify right)
			)
		)
		(property "Value" "C_2u2_0603_25V"
			(at 91.44 43.18 0)
			(effects
				(font
					(size 1.27 1.27)
					(thickness 0.15)
				)
				(justify left bottom)
				(hide yes)
			)
		)
		(property "Footprint" "antmicro-footprints:C_0603_1608Metric"
			(at 93.98 43.18 0)
			(effects
				(font
					(size 1.27 1.27)
					(thickness 0.15)
				)
				(justify left bottom)
				(hide yes)
			)
		)
		(property "Datasheet" "https://www.murata.com/products/productdetail?partno=GRM188R61E225KA12%23"
			(at 96.52 43.18 0)
			(effects
				(font
					(size 1.27 1.27)
					(thickness 0.15)
				)
				(justify left bottom)
				(hide yes)
			)
		)
		(property "Description" "SMD Multilayer Ceramic Capacitor, 2.2 µF, 25 V, 0603 [1608 Metric], ± 10%, X5R, GRM Series"
			(at 81.28 63.5 0)
			(effects
				(font
					(size 1.27 1.27)
				)
				(hide yes)
			)
		)
		(property "Manufacturer" "Murata"
			(at 101.6 43.18 0)
			(effects
				(font
					(size 1.27 1.27)
					(thickness 0.15)
				)
				(justify left bottom)
				(hide yes)
			)
		)
		(property "MPN" "GRM188R61E225KA12D"
			(at 99.06 43.18 0)
			(effects
				(font
					(size 1.27 1.27)
					(thickness 0.15)
				)
				(justify left bottom)
				(hide yes)
			)
		)
		(property "Val" "2u2"
			(at 81.915 62.865 90)
			(effects
				(font
					(size 1.27 1.27)
					(thickness 0.15)
				)
				(justify right)
			)
		)
		(property "License" "Apache-2.0"
			(at 104.14 43.18 0)
			(effects
				(font
					(size 1.27 1.27)
					(thickness 0.15)
				)
				(justify left bottom)
				(hide yes)
			)
		)
		(property "Author" "Antmicro"
			(at 106.68 43.18 0)
			(effects
				(font
					(size 1.27 1.27)
					(thickness 0.15)
				)
				(justify left bottom)
				(hide yes)
			)
		)
		(property "Voltage" ""
			(at 109.22 43.18 0)
			(effects
				(font
					(size 1.27 1.27)
				)
				(justify left bottom)
				(hide yes)
			)
		)
		(property "Dielectric" ""
			(at 111.76 43.18 0)
			(effects
				(font
					(size 1.27 1.27)
				)
				(justify left bottom)
				(hide yes)
			)
		)
		(property "Public" "False"
			(at 114.3 43.18 0)
			(effects
				(font
					(size 1.27 1.27)
				)
				(justify left bottom)
				(hide yes)
			)
		)
		(pin "1"
		)
		(pin "2"
		)
		(instances
			(project "artix-dc-scm"
				(path ""
					(reference "C66")
					(unit 1)
				)
			)
		)
	)
	(symbol
		(lib_id "antmicroCapacitorsmisc:C_2u2_0603_25V")
		(at 87.63 63.5 90)
		(unit 1)
		(exclude_from_sim no)
		(in_bom yes)
		(on_board yes)
		(dnp no)
		(property "Reference" "C67"
			(at 88.265 59.055 90)
			(effects
				(font
					(size 1.27 1.27)
				)
				(justify right)
			)
		)
		(property "Value" "C_2u2_0603_25V"
			(at 97.79 43.18 0)
			(effects
				(font
					(size 1.27 1.27)
					(thickness 0.15)
				)
				(justify left bottom)
				(hide yes)
			)
		)
		(property "Footprint" "antmicro-footprints:C_0603_1608Metric"
			(at 100.33 43.18 0)
			(effects
				(font
					(size 1.27 1.27)
					(thickness 0.15)
				)
				(justify left bottom)
				(hide yes)
			)
		)
		(property "Datasheet" "https://www.murata.com/products/productdetail?partno=GRM188R61E225KA12%23"
			(at 102.87 43.18 0)
			(effects
				(font
					(size 1.27 1.27)
					(thickness 0.15)
				)
				(justify left bottom)
				(hide yes)
			)
		)
		(property "Description" "SMD Multilayer Ceramic Capacitor, 2.2 µF, 25 V, 0603 [1608 Metric], ± 10%, X5R, GRM Series"
			(at 87.63 63.5 0)
			(effects
				(font
					(size 1.27 1.27)
				)
				(hide yes)
			)
		)
		(property "Manufacturer" "Murata"
			(at 107.95 43.18 0)
			(effects
				(font
					(size 1.27 1.27)
					(thickness 0.15)
				)
				(justify left bottom)
				(hide yes)
			)
		)
		(property "MPN" "GRM188R61E225KA12D"
			(at 105.41 43.18 0)
			(effects
				(font
					(size 1.27 1.27)
					(thickness 0.15)
				)
				(justify left bottom)
				(hide yes)
			)
		)
		(property "Val" "2u2"
			(at 88.265 62.865 90)
			(effects
				(font
					(size 1.27 1.27)
					(thickness 0.15)
				)
				(justify right)
			)
		)
		(property "License" "Apache-2.0"
			(at 110.49 43.18 0)
			(effects
				(font
					(size 1.27 1.27)
					(thickness 0.15)
				)
				(justify left bottom)
				(hide yes)
			)
		)
		(property "Author" "Antmicro"
			(at 113.03 43.18 0)
			(effects
				(font
					(size 1.27 1.27)
					(thickness 0.15)
				)
				(justify left bottom)
				(hide yes)
			)
		)
		(property "Voltage" ""
			(at 115.57 43.18 0)
			(effects
				(font
					(size 1.27 1.27)
				)
				(justify left bottom)
				(hide yes)
			)
		)
		(property "Dielectric" ""
			(at 118.11 43.18 0)
			(effects
				(font
					(size 1.27 1.27)
				)
				(justify left bottom)
				(hide yes)
			)
		)
		(property "Public" "False"
			(at 120.65 43.18 0)
			(effects
				(font
					(size 1.27 1.27)
				)
				(justify left bottom)
				(hide yes)
			)
		)
		(pin "1"
		)
		(pin "2"
		)
		(instances
			(project "artix-dc-scm"
				(path ""
					(reference "C67")
					(unit 1)
				)
			)
		)
	)
	(symbol
		(lib_id "antmicroTestPoints:TP_1mm_SMD")
		(at 87.63 76.2 180)
		(unit 1)
		(exclude_from_sim no)
		(in_bom no)
		(on_board yes)
		(dnp no)
		(property "Reference" "TP1"
			(at 81.28 76.2 0)
			(effects
				(font
					(size 1.27 1.27)
				)
			)
		)
		(property "Value" "TP_1mm_SMD"
			(at 87.63 73.66 0)
			(effects
				(font
					(size 1.27 1.27)
				)
				(hide yes)
			)
		)
		(property "Footprint" "antmicro-footprints:TP_SMD_1mm"
			(at 72.39 66.04 0)
			(effects
				(font
					(size 1.27 1.27)
					(thickness 0.15)
				)
				(justify left bottom)
				(hide yes)
			)
		)
		(property "Datasheet" ""
			(at 72.39 63.5 0)
			(effects
				(font
					(size 1.27 1.27)
					(thickness 0.15)
				)
				(justify left bottom)
				(hide yes)
			)
		)
		(property "Description" "Test point 1mm SMD"
			(at 87.63 76.2 0)
			(effects
				(font
					(size 1.27 1.27)
				)
				(hide yes)
			)
		)
		(property "MPN" ""
			(at 87.63 76.2 0)
			(effects
				(font
					(size 1.27 1.27)
				)
				(hide yes)
			)
		)
		(property "Manufacturer" ""
			(at 87.63 76.2 0)
			(effects
				(font
					(size 1.27 1.27)
				)
				(hide yes)
			)
		)
		(property "Author" "Antmicro"
			(at 72.39 60.96 0)
			(effects
				(font
					(size 1.27 1.27)
					(thickness 0.15)
				)
				(justify left bottom)
				(hide yes)
			)
		)
		(property "License" "Apache-2.0"
			(at 72.39 58.42 0)
			(effects
				(font
					(size 1.27 1.27)
					(thickness 0.15)
				)
				(justify left bottom)
				(hide yes)
			)
		)
		(pin "1"
		)
		(instances
			(project "artix-dc-scm"
				(path ""
					(reference "TP1")
					(unit 1)
				)
			)
		)
	)
	(symbol
		(lib_id "antmicropower:GND")
		(at 81.28 63.5 0)
		(unit 1)
		(exclude_from_sim no)
		(in_bom yes)
		(on_board yes)
		(dnp no)
		(property "Reference" "#PWR051"
			(at 81.28 69.85 0)
			(effects
				(font
					(size 1.27 1.27)
				)
				(hide yes)
			)
		)
		(property "Value" "GND"
			(at 81.28 67.31 0)
			(effects
				(font
					(size 1.27 1.27)
				)
			)
		)
		(property "Footprint" ""
			(at 81.28 63.5 0)
			(effects
				(font
					(size 1.27 1.27)
				)
				(hide yes)
			)
		)
		(property "Datasheet" ""
			(at 81.28 63.5 0)
			(effects
				(font
					(size 1.27 1.27)
				)
				(hide yes)
			)
		)
		(property "Description" ""
			(at 81.28 63.5 0)
			(effects
				(font
					(size 1.27 1.27)
				)
				(hide yes)
			)
		)
		(property "Author" "Antmicro"
			(at 90.17 71.12 0)
			(effects
				(font
					(size 1.27 1.27)
					(thickness 0.15)
				)
				(justify left bottom)
				(hide yes)
			)
		)
		(property "License" "Apache-2.0"
			(at 90.17 73.66 0)
			(effects
				(font
					(size 1.27 1.27)
					(thickness 0.15)
				)
				(justify left bottom)
				(hide yes)
			)
		)
		(pin "1"
		)
		(instances
			(project "artix-dc-scm"
				(path ""
					(reference "#PWR051")
					(unit 1)
				)
			)
		)
	)
	(symbol
		(lib_id "antmicropower:GND")
		(at 74.93 63.5 0)
		(unit 1)
		(exclude_from_sim no)
		(in_bom yes)
		(on_board yes)
		(dnp no)
		(property "Reference" "#PWR050"
			(at 74.93 69.85 0)
			(effects
				(font
					(size 1.27 1.27)
				)
				(hide yes)
			)
		)
		(property "Value" "GND"
			(at 74.93 67.31 0)
			(effects
				(font
					(size 1.27 1.27)
				)
			)
		)
		(property "Footprint" ""
			(at 74.93 63.5 0)
			(effects
				(font
					(size 1.27 1.27)
				)
				(hide yes)
			)
		)
		(property "Datasheet" ""
			(at 74.93 63.5 0)
			(effects
				(font
					(size 1.27 1.27)
				)
				(hide yes)
			)
		)
		(property "Description" ""
			(at 74.93 63.5 0)
			(effects
				(font
					(size 1.27 1.27)
				)
				(hide yes)
			)
		)
		(property "Author" "Antmicro"
			(at 83.82 71.12 0)
			(effects
				(font
					(size 1.27 1.27)
					(thickness 0.15)
				)
				(justify left bottom)
				(hide yes)
			)
		)
		(property "License" "Apache-2.0"
			(at 83.82 73.66 0)
			(effects
				(font
					(size 1.27 1.27)
					(thickness 0.15)
				)
				(justify left bottom)
				(hide yes)
			)
		)
		(pin "1"
		)
		(instances
			(project "artix-dc-scm"
				(path ""
					(reference "#PWR050")
					(unit 1)
				)
			)
		)
	)
	(symbol
		(lib_id "antmicropower:GND")
		(at 87.63 63.5 0)
		(unit 1)
		(exclude_from_sim no)
		(in_bom yes)
		(on_board yes)
		(dnp no)
		(property "Reference" "#PWR052"
			(at 87.63 69.85 0)
			(effects
				(font
					(size 1.27 1.27)
				)
				(hide yes)
			)
		)
		(property "Value" "GND"
			(at 87.63 67.31 0)
			(effects
				(font
					(size 1.27 1.27)
				)
			)
		)
		(property "Footprint" ""
			(at 87.63 63.5 0)
			(effects
				(font
					(size 1.27 1.27)
				)
				(hide yes)
			)
		)
		(property "Datasheet" ""
			(at 87.63 63.5 0)
			(effects
				(font
					(size 1.27 1.27)
				)
				(hide yes)
			)
		)
		(property "Description" ""
			(at 87.63 63.5 0)
			(effects
				(font
					(size 1.27 1.27)
				)
				(hide yes)
			)
		)
		(property "Author" "Antmicro"
			(at 96.52 71.12 0)
			(effects
				(font
					(size 1.27 1.27)
					(thickness 0.15)
				)
				(justify left bottom)
				(hide yes)
			)
		)
		(property "License" "Apache-2.0"
			(at 96.52 73.66 0)
			(effects
				(font
					(size 1.27 1.27)
					(thickness 0.15)
				)
				(justify left bottom)
				(hide yes)
			)
		)
		(pin "1"
		)
		(instances
			(project "artix-dc-scm"
				(path ""
					(reference "#PWR052")
					(unit 1)
				)
			)
		)
	)
	(symbol
		(lib_id "antmicroResistors0402:R_243k_0402")
		(at 80.01 90.17 90)
		(unit 1)
		(exclude_from_sim no)
		(in_bom yes)
		(on_board yes)
		(dnp no)
		(property "Reference" "R67"
			(at 81.28 86.36 90)
			(effects
				(font
					(size 1.27 1.27)
				)
				(justify right)
			)
		)
		(property "Value" "R_243k_0402"
			(at 92.71 69.85 0)
			(effects
				(font
					(size 1.27 1.27)
					(thickness 0.15)
				)
				(justify left bottom)
				(hide yes)
			)
		)
		(property "Footprint" "antmicro-footprints:R_0402_1005Metric"
			(at 95.25 69.85 0)
			(effects
				(font
					(size 1.27 1.27)
					(thickness 0.15)
				)
				(justify left bottom)
				(hide yes)
			)
		)
		(property "Datasheet" "https://www.bourns.com/docs/product-datasheets/cr.pdf"
			(at 97.79 69.85 0)
			(effects
				(font
					(size 1.27 1.27)
					(thickness 0.15)
				)
				(justify left bottom)
				(hide yes)
			)
		)
		(property "Description" "SMD Chip Resistor"
			(at 80.01 90.17 0)
			(effects
				(font
					(size 1.27 1.27)
				)
				(hide yes)
			)
		)
		(property "Manufacturer" "Bourns"
			(at 102.87 69.85 0)
			(effects
				(font
					(size 1.27 1.27)
					(thickness 0.15)
				)
				(justify left bottom)
				(hide yes)
			)
		)
		(property "MPN" "CR0402-FX-2433GLF"
			(at 100.33 69.85 0)
			(effects
				(font
					(size 1.27 1.27)
					(thickness 0.15)
				)
				(justify left bottom)
				(hide yes)
			)
		)
		(property "Val" "243k"
			(at 81.28 88.9 90)
			(effects
				(font
					(size 1.27 1.27)
					(thickness 0.15)
				)
				(justify right)
			)
		)
		(property "License" "Apache-2.0"
			(at 105.41 69.85 0)
			(effects
				(font
					(size 1.27 1.27)
					(thickness 0.15)
				)
				(justify left bottom)
				(hide yes)
			)
		)
		(property "Author" "Antmicro"
			(at 107.95 69.85 0)
			(effects
				(font
					(size 1.27 1.27)
					(thickness 0.15)
				)
				(justify left bottom)
				(hide yes)
			)
		)
		(property "Tolerance" "1%"
			(at 90.17 69.85 0)
			(effects
				(font
					(size 1.27 1.27)
				)
				(justify left bottom)
				(hide yes)
			)
		)
		(pin "1"
		)
		(pin "2"
		)
		(instances
			(project "artix-dc-scm"
				(path ""
					(reference "R67")
					(unit 1)
				)
			)
		)
	)
	(symbol
		(lib_id "antmicroCapacitors0402:C_10n_0402")
		(at 88.9 90.17 90)
		(unit 1)
		(exclude_from_sim no)
		(in_bom yes)
		(on_board yes)
		(dnp no)
		(property "Reference" "C69"
			(at 89.535 85.725 90)
			(effects
				(font
					(size 1.27 1.27)
				)
				(justify right)
			)
		)
		(property "Value" "C_10n_0402"
			(at 99.06 69.85 0)
			(effects
				(font
					(size 1.27 1.27)
					(thickness 0.15)
				)
				(justify left bottom)
				(hide yes)
			)
		)
		(property "Footprint" "antmicro-footprints:C_0402_1005Metric"
			(at 101.6 69.85 0)
			(effects
				(font
					(size 1.27 1.27)
					(thickness 0.15)
				)
				(justify left bottom)
				(hide yes)
			)
		)
		(property "Datasheet" "https://www.murata.com/products/productdetail?partno=GRM155R71H103KA88%23"
			(at 104.14 69.85 0)
			(effects
				(font
					(size 1.27 1.27)
					(thickness 0.15)
				)
				(justify left bottom)
				(hide yes)
			)
		)
		(property "Description" "SMD Multilayer Ceramic Capacitor, 10000 pF, 50 V, 0402 [1005 Metric], ± 10%, X7R, GRM Series"
			(at 88.9 90.17 0)
			(effects
				(font
					(size 1.27 1.27)
				)
				(hide yes)
			)
		)
		(property "Manufacturer" "Murata"
			(at 109.22 69.85 0)
			(effects
				(font
					(size 1.27 1.27)
					(thickness 0.15)
				)
				(justify left bottom)
				(hide yes)
			)
		)
		(property "MPN" "GRM155R71H103KA88D"
			(at 106.68 69.85 0)
			(effects
				(font
					(size 1.27 1.27)
					(thickness 0.15)
				)
				(justify left bottom)
				(hide yes)
			)
		)
		(property "Val" "10n"
			(at 89.535 89.535 90)
			(effects
				(font
					(size 1.27 1.27)
					(thickness 0.15)
				)
				(justify right)
			)
		)
		(property "License" "Apache-2.0"
			(at 111.76 69.85 0)
			(effects
				(font
					(size 1.27 1.27)
					(thickness 0.15)
				)
				(justify left bottom)
				(hide yes)
			)
		)
		(property "Author" "Antmicro"
			(at 114.3 69.85 0)
			(effects
				(font
					(size 1.27 1.27)
					(thickness 0.15)
				)
				(justify left bottom)
				(hide yes)
			)
		)
		(property "Voltage" "50V"
			(at 116.84 69.85 0)
			(effects
				(font
					(size 1.27 1.27)
				)
				(justify left bottom)
				(hide yes)
			)
		)
		(property "Dielectric" "X7R"
			(at 119.38 69.85 0)
			(effects
				(font
					(size 1.27 1.27)
				)
				(justify left bottom)
				(hide yes)
			)
		)
		(pin "1"
		)
		(pin "2"
		)
		(instances
			(project "artix-dc-scm"
				(path ""
					(reference "C69")
					(unit 1)
				)
			)
		)
	)
	(symbol
		(lib_id "antmicropower:GND")
		(at 238.76 76.2 0)
		(unit 1)
		(exclude_from_sim no)
		(in_bom yes)
		(on_board yes)
		(dnp no)
		(property "Reference" "#PWR0103"
			(at 238.76 82.55 0)
			(effects
				(font
					(size 1.27 1.27)
				)
				(hide yes)
			)
		)
		(property "Value" "GND"
			(at 238.76 80.01 0)
			(effects
				(font
					(size 1.27 1.27)
				)
			)
		)
		(property "Footprint" ""
			(at 238.76 76.2 0)
			(effects
				(font
					(size 1.27 1.27)
				)
				(hide yes)
			)
		)
		(property "Datasheet" ""
			(at 238.76 76.2 0)
			(effects
				(font
					(size 1.27 1.27)
				)
				(hide yes)
			)
		)
		(property "Description" ""
			(at 238.76 76.2 0)
			(effects
				(font
					(size 1.27 1.27)
				)
				(hide yes)
			)
		)
		(property "Author" "Antmicro"
			(at 247.65 83.82 0)
			(effects
				(font
					(size 1.27 1.27)
					(thickness 0.15)
				)
				(justify left bottom)
				(hide yes)
			)
		)
		(property "License" "Apache-2.0"
			(at 247.65 86.36 0)
			(effects
				(font
					(size 1.27 1.27)
					(thickness 0.15)
				)
				(justify left bottom)
				(hide yes)
			)
		)
		(pin "1"
		)
		(instances
			(project "artix-dc-scm"
				(path ""
					(reference "#PWR0103")
					(unit 1)
				)
			)
		)
	)
	(symbol
		(lib_id "antmicroResistors0402:R_10k_0402")
		(at 226.06 66.04 270)
		(unit 1)
		(exclude_from_sim no)
		(in_bom yes)
		(on_board yes)
		(dnp no)
		(property "Reference" "R93"
			(at 227.33 67.31 90)
			(effects
				(font
					(size 1.27 1.27)
				)
				(justify left)
			)
		)
		(property "Value" "R_10k_0402"
			(at 213.36 86.36 0)
			(effects
				(font
					(size 1.27 1.27)
					(thickness 0.15)
				)
				(justify left bottom)
				(hide yes)
			)
		)
		(property "Footprint" "antmicro-footprints:R_0402_1005Metric"
			(at 210.82 86.36 0)
			(effects
				(font
					(size 1.27 1.27)
					(thickness 0.15)
				)
				(justify left bottom)
				(hide yes)
			)
		)
		(property "Datasheet" "https://www.bourns.com/docs/product-datasheets/cr.pdf"
			(at 208.28 86.36 0)
			(effects
				(font
					(size 1.27 1.27)
					(thickness 0.15)
				)
				(justify left bottom)
				(hide yes)
			)
		)
		(property "Description" "SMD Chip Resistor, 10 kohm, ± 1%, 62.5 mW, 0402 [1005 Metric], Thick Film, General Purpose"
			(at 226.06 66.04 0)
			(effects
				(font
					(size 1.27 1.27)
				)
				(hide yes)
			)
		)
		(property "Manufacturer" "Bourns"
			(at 203.2 86.36 0)
			(effects
				(font
					(size 1.27 1.27)
					(thickness 0.15)
				)
				(justify left bottom)
				(hide yes)
			)
		)
		(property "MPN" "CR0402-FX-1002GLF"
			(at 205.74 86.36 0)
			(effects
				(font
					(size 1.27 1.27)
					(thickness 0.15)
				)
				(justify left bottom)
				(hide yes)
			)
		)
		(property "Val" "10k"
			(at 227.33 69.85 90)
			(effects
				(font
					(size 1.27 1.27)
					(thickness 0.15)
				)
				(justify left)
			)
		)
		(property "License" "Apache-2.0"
			(at 200.66 86.36 0)
			(effects
				(font
					(size 1.27 1.27)
					(thickness 0.15)
				)
				(justify left bottom)
				(hide yes)
			)
		)
		(property "Author" "Antmicro"
			(at 198.12 86.36 0)
			(effects
				(font
					(size 1.27 1.27)
					(thickness 0.15)
				)
				(justify left bottom)
				(hide yes)
			)
		)
		(property "Tolerance" "1%"
			(at 215.9 86.36 0)
			(effects
				(font
					(size 1.27 1.27)
				)
				(justify left bottom)
				(hide yes)
			)
		)
		(pin "1"
		)
		(pin "2"
		)
		(instances
			(project "artix-dc-scm"
				(path ""
					(reference "R93")
					(unit 1)
				)
			)
		)
	)
	(symbol
		(lib_id "antmicroResistors0402:R_1k_0402")
		(at 260.35 62.23 0)
		(unit 1)
		(exclude_from_sim no)
		(in_bom yes)
		(on_board yes)
		(dnp no)
		(property "Reference" "R98"
			(at 262.89 59.69 0)
			(effects
				(font
					(size 1.27 1.27)
				)
			)
		)
		(property "Value" "R_1k_0402"
			(at 280.67 74.93 0)
			(effects
				(font
					(size 1.27 1.27)
					(thickness 0.15)
				)
				(justify left bottom)
				(hide yes)
			)
		)
		(property "Footprint" "antmicro-footprints:R_0402_1005Metric"
			(at 280.67 77.47 0)
			(effects
				(font
					(size 1.27 1.27)
					(thickness 0.15)
				)
				(justify left bottom)
				(hide yes)
			)
		)
		(property "Datasheet" "https://www.bourns.com/docs/product-datasheets/cr.pdf"
			(at 280.67 80.01 0)
			(effects
				(font
					(size 1.27 1.27)
					(thickness 0.15)
				)
				(justify left bottom)
				(hide yes)
			)
		)
		(property "Description" "SMD Chip Resistor, 1 kohm, ± 1%, 63 mW, 0402 [1005 Metric], Thick Film, General Purpose"
			(at 260.35 62.23 0)
			(effects
				(font
					(size 1.27 1.27)
				)
				(hide yes)
			)
		)
		(property "Manufacturer" "Bourns"
			(at 280.67 85.09 0)
			(effects
				(font
					(size 1.27 1.27)
					(thickness 0.15)
				)
				(justify left bottom)
				(hide yes)
			)
		)
		(property "MPN" "CR0402-FX-1001GLF"
			(at 280.67 82.55 0)
			(effects
				(font
					(size 1.27 1.27)
					(thickness 0.15)
				)
				(justify left bottom)
				(hide yes)
			)
		)
		(property "Val" "1k"
			(at 262.89 64.77 0)
			(effects
				(font
					(size 1.27 1.27)
					(thickness 0.15)
				)
			)
		)
		(property "License" "Apache-2.0"
			(at 280.67 87.63 0)
			(effects
				(font
					(size 1.27 1.27)
					(thickness 0.15)
				)
				(justify left bottom)
				(hide yes)
			)
		)
		(property "Author" "Antmicro"
			(at 280.67 90.17 0)
			(effects
				(font
					(size 1.27 1.27)
					(thickness 0.15)
				)
				(justify left bottom)
				(hide yes)
			)
		)
		(property "Tolerance" "1%"
			(at 280.67 72.39 0)
			(effects
				(font
					(size 1.27 1.27)
				)
				(justify left bottom)
				(hide yes)
			)
		)
		(pin "1"
		)
		(pin "2"
		)
		(instances
			(project "artix-dc-scm"
				(path ""
					(reference "R98")
					(unit 1)
				)
			)
		)
	)
	(symbol
		(lib_id "antmicropower:GND")
		(at 237.49 107.95 0)
		(unit 1)
		(exclude_from_sim no)
		(in_bom yes)
		(on_board yes)
		(dnp no)
		(property "Reference" "#PWR0104"
			(at 237.49 114.3 0)
			(effects
				(font
					(size 1.27 1.27)
				)
				(hide yes)
			)
		)
		(property "Value" "GND"
			(at 237.49 111.76 0)
			(effects
				(font
					(size 1.27 1.27)
				)
			)
		)
		(property "Footprint" ""
			(at 237.49 107.95 0)
			(effects
				(font
					(size 1.27 1.27)
				)
				(hide yes)
			)
		)
		(property "Datasheet" ""
			(at 237.49 107.95 0)
			(effects
				(font
					(size 1.27 1.27)
				)
				(hide yes)
			)
		)
		(property "Description" ""
			(at 237.49 107.95 0)
			(effects
				(font
					(size 1.27 1.27)
				)
				(hide yes)
			)
		)
		(property "Author" "Antmicro"
			(at 246.38 115.57 0)
			(effects
				(font
					(size 1.27 1.27)
					(thickness 0.15)
				)
				(justify left bottom)
				(hide yes)
			)
		)
		(property "License" "Apache-2.0"
			(at 246.38 118.11 0)
			(effects
				(font
					(size 1.27 1.27)
					(thickness 0.15)
				)
				(justify left bottom)
				(hide yes)
			)
		)
		(pin "1"
		)
		(instances
			(project "artix-dc-scm"
				(path ""
					(reference "#PWR0104")
					(unit 1)
				)
			)
		)
	)
	(symbol
		(lib_id "antmicroResistors0402:R_10k_0402")
		(at 224.79 97.79 270)
		(unit 1)
		(exclude_from_sim no)
		(in_bom yes)
		(on_board yes)
		(dnp no)
		(property "Reference" "R91"
			(at 226.06 99.06 90)
			(effects
				(font
					(size 1.27 1.27)
				)
				(justify left)
			)
		)
		(property "Value" "R_10k_0402"
			(at 212.09 118.11 0)
			(effects
				(font
					(size 1.27 1.27)
					(thickness 0.15)
				)
				(justify left bottom)
				(hide yes)
			)
		)
		(property "Footprint" "antmicro-footprints:R_0402_1005Metric"
			(at 209.55 118.11 0)
			(effects
				(font
					(size 1.27 1.27)
					(thickness 0.15)
				)
				(justify left bottom)
				(hide yes)
			)
		)
		(property "Datasheet" "https://www.bourns.com/docs/product-datasheets/cr.pdf"
			(at 207.01 118.11 0)
			(effects
				(font
					(size 1.27 1.27)
					(thickness 0.15)
				)
				(justify left bottom)
				(hide yes)
			)
		)
		(property "Description" "SMD Chip Resistor, 10 kohm, ± 1%, 62.5 mW, 0402 [1005 Metric], Thick Film, General Purpose"
			(at 224.79 97.79 0)
			(effects
				(font
					(size 1.27 1.27)
				)
				(hide yes)
			)
		)
		(property "Manufacturer" "Bourns"
			(at 201.93 118.11 0)
			(effects
				(font
					(size 1.27 1.27)
					(thickness 0.15)
				)
				(justify left bottom)
				(hide yes)
			)
		)
		(property "MPN" "CR0402-FX-1002GLF"
			(at 204.47 118.11 0)
			(effects
				(font
					(size 1.27 1.27)
					(thickness 0.15)
				)
				(justify left bottom)
				(hide yes)
			)
		)
		(property "Val" "10k"
			(at 226.06 101.6 90)
			(effects
				(font
					(size 1.27 1.27)
					(thickness 0.15)
				)
				(justify left)
			)
		)
		(property "License" "Apache-2.0"
			(at 199.39 118.11 0)
			(effects
				(font
					(size 1.27 1.27)
					(thickness 0.15)
				)
				(justify left bottom)
				(hide yes)
			)
		)
		(property "Author" "Antmicro"
			(at 196.85 118.11 0)
			(effects
				(font
					(size 1.27 1.27)
					(thickness 0.15)
				)
				(justify left bottom)
				(hide yes)
			)
		)
		(property "Tolerance" "1%"
			(at 214.63 118.11 0)
			(effects
				(font
					(size 1.27 1.27)
				)
				(justify left bottom)
				(hide yes)
			)
		)
		(pin "1"
		)
		(pin "2"
		)
		(instances
			(project "artix-dc-scm"
				(path ""
					(reference "R91")
					(unit 1)
				)
			)
		)
	)
	(symbol
		(lib_id "antmicroResistors0402:R_1k_0402")
		(at 260.35 93.98 0)
		(unit 1)
		(exclude_from_sim no)
		(in_bom yes)
		(on_board yes)
		(dnp no)
		(property "Reference" "R96"
			(at 262.89 91.44 0)
			(effects
				(font
					(size 1.27 1.27)
				)
			)
		)
		(property "Value" "R_1k_0402"
			(at 280.67 106.68 0)
			(effects
				(font
					(size 1.27 1.27)
					(thickness 0.15)
				)
				(justify left bottom)
				(hide yes)
			)
		)
		(property "Footprint" "antmicro-footprints:R_0402_1005Metric"
			(at 280.67 109.22 0)
			(effects
				(font
					(size 1.27 1.27)
					(thickness 0.15)
				)
				(justify left bottom)
				(hide yes)
			)
		)
		(property "Datasheet" "https://www.bourns.com/docs/product-datasheets/cr.pdf"
			(at 280.67 111.76 0)
			(effects
				(font
					(size 1.27 1.27)
					(thickness 0.15)
				)
				(justify left bottom)
				(hide yes)
			)
		)
		(property "Description" "SMD Chip Resistor, 1 kohm, ± 1%, 63 mW, 0402 [1005 Metric], Thick Film, General Purpose"
			(at 260.35 93.98 0)
			(effects
				(font
					(size 1.27 1.27)
				)
				(hide yes)
			)
		)
		(property "Manufacturer" "Bourns"
			(at 280.67 116.84 0)
			(effects
				(font
					(size 1.27 1.27)
					(thickness 0.15)
				)
				(justify left bottom)
				(hide yes)
			)
		)
		(property "MPN" "CR0402-FX-1001GLF"
			(at 280.67 114.3 0)
			(effects
				(font
					(size 1.27 1.27)
					(thickness 0.15)
				)
				(justify left bottom)
				(hide yes)
			)
		)
		(property "Val" "1k"
			(at 262.89 96.52 0)
			(effects
				(font
					(size 1.27 1.27)
					(thickness 0.15)
				)
			)
		)
		(property "License" "Apache-2.0"
			(at 280.67 119.38 0)
			(effects
				(font
					(size 1.27 1.27)
					(thickness 0.15)
				)
				(justify left bottom)
				(hide yes)
			)
		)
		(property "Author" "Antmicro"
			(at 280.67 121.92 0)
			(effects
				(font
					(size 1.27 1.27)
					(thickness 0.15)
				)
				(justify left bottom)
				(hide yes)
			)
		)
		(property "Tolerance" "1%"
			(at 280.67 104.14 0)
			(effects
				(font
					(size 1.27 1.27)
				)
				(justify left bottom)
				(hide yes)
			)
		)
		(pin "1"
		)
		(pin "2"
		)
		(instances
			(project "artix-dc-scm"
				(path ""
					(reference "R96")
					(unit 1)
				)
			)
		)
	)
	(symbol
		(lib_id "antmicropower:GND")
		(at 237.49 138.43 0)
		(unit 1)
		(exclude_from_sim no)
		(in_bom yes)
		(on_board yes)
		(dnp no)
		(property "Reference" "#PWR0105"
			(at 237.49 144.78 0)
			(effects
				(font
					(size 1.27 1.27)
				)
				(hide yes)
			)
		)
		(property "Value" "GND"
			(at 237.49 142.24 0)
			(effects
				(font
					(size 1.27 1.27)
				)
			)
		)
		(property "Footprint" ""
			(at 237.49 138.43 0)
			(effects
				(font
					(size 1.27 1.27)
				)
				(hide yes)
			)
		)
		(property "Datasheet" ""
			(at 237.49 138.43 0)
			(effects
				(font
					(size 1.27 1.27)
				)
				(hide yes)
			)
		)
		(property "Description" ""
			(at 237.49 138.43 0)
			(effects
				(font
					(size 1.27 1.27)
				)
				(hide yes)
			)
		)
		(property "Author" "Antmicro"
			(at 246.38 146.05 0)
			(effects
				(font
					(size 1.27 1.27)
					(thickness 0.15)
				)
				(justify left bottom)
				(hide yes)
			)
		)
		(property "License" "Apache-2.0"
			(at 246.38 148.59 0)
			(effects
				(font
					(size 1.27 1.27)
					(thickness 0.15)
				)
				(justify left bottom)
				(hide yes)
			)
		)
		(pin "1"
		)
		(instances
			(project "artix-dc-scm"
				(path ""
					(reference "#PWR0105")
					(unit 1)
				)
			)
		)
	)
	(symbol
		(lib_id "antmicroResistors0402:R_10k_0402")
		(at 224.79 128.27 270)
		(unit 1)
		(exclude_from_sim no)
		(in_bom yes)
		(on_board yes)
		(dnp no)
		(property "Reference" "R92"
			(at 226.06 129.54 90)
			(effects
				(font
					(size 1.27 1.27)
				)
				(justify left)
			)
		)
		(property "Value" "R_10k_0402"
			(at 212.09 148.59 0)
			(effects
				(font
					(size 1.27 1.27)
					(thickness 0.15)
				)
				(justify left bottom)
				(hide yes)
			)
		)
		(property "Footprint" "antmicro-footprints:R_0402_1005Metric"
			(at 209.55 148.59 0)
			(effects
				(font
					(size 1.27 1.27)
					(thickness 0.15)
				)
				(justify left bottom)
				(hide yes)
			)
		)
		(property "Datasheet" "https://www.bourns.com/docs/product-datasheets/cr.pdf"
			(at 207.01 148.59 0)
			(effects
				(font
					(size 1.27 1.27)
					(thickness 0.15)
				)
				(justify left bottom)
				(hide yes)
			)
		)
		(property "Description" "SMD Chip Resistor, 10 kohm, ± 1%, 62.5 mW, 0402 [1005 Metric], Thick Film, General Purpose"
			(at 224.79 128.27 0)
			(effects
				(font
					(size 1.27 1.27)
				)
				(hide yes)
			)
		)
		(property "Manufacturer" "Bourns"
			(at 201.93 148.59 0)
			(effects
				(font
					(size 1.27 1.27)
					(thickness 0.15)
				)
				(justify left bottom)
				(hide yes)
			)
		)
		(property "MPN" "CR0402-FX-1002GLF"
			(at 204.47 148.59 0)
			(effects
				(font
					(size 1.27 1.27)
					(thickness 0.15)
				)
				(justify left bottom)
				(hide yes)
			)
		)
		(property "Val" "10k"
			(at 226.06 132.08 90)
			(effects
				(font
					(size 1.27 1.27)
					(thickness 0.15)
				)
				(justify left)
			)
		)
		(property "License" "Apache-2.0"
			(at 199.39 148.59 0)
			(effects
				(font
					(size 1.27 1.27)
					(thickness 0.15)
				)
				(justify left bottom)
				(hide yes)
			)
		)
		(property "Author" "Antmicro"
			(at 196.85 148.59 0)
			(effects
				(font
					(size 1.27 1.27)
					(thickness 0.15)
				)
				(justify left bottom)
				(hide yes)
			)
		)
		(property "Tolerance" "1%"
			(at 214.63 148.59 0)
			(effects
				(font
					(size 1.27 1.27)
				)
				(justify left bottom)
				(hide yes)
			)
		)
		(pin "1"
		)
		(pin "2"
		)
		(instances
			(project "artix-dc-scm"
				(path ""
					(reference "R92")
					(unit 1)
				)
			)
		)
	)
	(symbol
		(lib_id "antmicroResistors0402:R_1k_0402")
		(at 260.35 124.46 0)
		(unit 1)
		(exclude_from_sim no)
		(in_bom yes)
		(on_board yes)
		(dnp no)
		(property "Reference" "R97"
			(at 262.89 121.92 0)
			(effects
				(font
					(size 1.27 1.27)
				)
			)
		)
		(property "Value" "R_1k_0402"
			(at 280.67 137.16 0)
			(effects
				(font
					(size 1.27 1.27)
					(thickness 0.15)
				)
				(justify left bottom)
				(hide yes)
			)
		)
		(property "Footprint" "antmicro-footprints:R_0402_1005Metric"
			(at 280.67 139.7 0)
			(effects
				(font
					(size 1.27 1.27)
					(thickness 0.15)
				)
				(justify left bottom)
				(hide yes)
			)
		)
		(property "Datasheet" "https://www.bourns.com/docs/product-datasheets/cr.pdf"
			(at 280.67 142.24 0)
			(effects
				(font
					(size 1.27 1.27)
					(thickness 0.15)
				)
				(justify left bottom)
				(hide yes)
			)
		)
		(property "Description" "SMD Chip Resistor, 1 kohm, ± 1%, 63 mW, 0402 [1005 Metric], Thick Film, General Purpose"
			(at 260.35 124.46 0)
			(effects
				(font
					(size 1.27 1.27)
				)
				(hide yes)
			)
		)
		(property "Manufacturer" "Bourns"
			(at 280.67 147.32 0)
			(effects
				(font
					(size 1.27 1.27)
					(thickness 0.15)
				)
				(justify left bottom)
				(hide yes)
			)
		)
		(property "MPN" "CR0402-FX-1001GLF"
			(at 280.67 144.78 0)
			(effects
				(font
					(size 1.27 1.27)
					(thickness 0.15)
				)
				(justify left bottom)
				(hide yes)
			)
		)
		(property "Val" "1k"
			(at 262.89 127 0)
			(effects
				(font
					(size 1.27 1.27)
					(thickness 0.15)
				)
			)
		)
		(property "License" "Apache-2.0"
			(at 280.67 149.86 0)
			(effects
				(font
					(size 1.27 1.27)
					(thickness 0.15)
				)
				(justify left bottom)
				(hide yes)
			)
		)
		(property "Author" "Antmicro"
			(at 280.67 152.4 0)
			(effects
				(font
					(size 1.27 1.27)
					(thickness 0.15)
				)
				(justify left bottom)
				(hide yes)
			)
		)
		(property "Tolerance" "1%"
			(at 280.67 134.62 0)
			(effects
				(font
					(size 1.27 1.27)
				)
				(justify left bottom)
				(hide yes)
			)
		)
		(pin "1"
		)
		(pin "2"
		)
		(instances
			(project "artix-dc-scm"
				(path ""
					(reference "R97")
					(unit 1)
				)
			)
		)
	)
	(symbol
		(lib_id "antmicroResistors0402:R_10k_0402")
		(at 223.52 161.29 270)
		(unit 1)
		(exclude_from_sim no)
		(in_bom yes)
		(on_board yes)
		(dnp no)
		(property "Reference" "R61"
			(at 224.79 162.56 90)
			(effects
				(font
					(size 1.27 1.27)
				)
				(justify left)
			)
		)
		(property "Value" "R_10k_0402"
			(at 210.82 181.61 0)
			(effects
				(font
					(size 1.27 1.27)
					(thickness 0.15)
				)
				(justify left bottom)
				(hide yes)
			)
		)
		(property "Footprint" "antmicro-footprints:R_0402_1005Metric"
			(at 208.28 181.61 0)
			(effects
				(font
					(size 1.27 1.27)
					(thickness 0.15)
				)
				(justify left bottom)
				(hide yes)
			)
		)
		(property "Datasheet" "https://www.bourns.com/docs/product-datasheets/cr.pdf"
			(at 205.74 181.61 0)
			(effects
				(font
					(size 1.27 1.27)
					(thickness 0.15)
				)
				(justify left bottom)
				(hide yes)
			)
		)
		(property "Description" "SMD Chip Resistor, 10 kohm, ± 1%, 62.5 mW, 0402 [1005 Metric], Thick Film, General Purpose"
			(at 223.52 161.29 0)
			(effects
				(font
					(size 1.27 1.27)
				)
				(hide yes)
			)
		)
		(property "Manufacturer" "Bourns"
			(at 200.66 181.61 0)
			(effects
				(font
					(size 1.27 1.27)
					(thickness 0.15)
				)
				(justify left bottom)
				(hide yes)
			)
		)
		(property "MPN" "CR0402-FX-1002GLF"
			(at 203.2 181.61 0)
			(effects
				(font
					(size 1.27 1.27)
					(thickness 0.15)
				)
				(justify left bottom)
				(hide yes)
			)
		)
		(property "Val" "10k"
			(at 224.79 165.1 90)
			(effects
				(font
					(size 1.27 1.27)
					(thickness 0.15)
				)
				(justify left)
			)
		)
		(property "License" "Apache-2.0"
			(at 198.12 181.61 0)
			(effects
				(font
					(size 1.27 1.27)
					(thickness 0.15)
				)
				(justify left bottom)
				(hide yes)
			)
		)
		(property "Author" "Antmicro"
			(at 195.58 181.61 0)
			(effects
				(font
					(size 1.27 1.27)
					(thickness 0.15)
				)
				(justify left bottom)
				(hide yes)
			)
		)
		(property "Tolerance" "1%"
			(at 213.36 181.61 0)
			(effects
				(font
					(size 1.27 1.27)
				)
				(justify left bottom)
				(hide yes)
			)
		)
		(pin "1"
		)
		(pin "2"
		)
		(instances
			(project "artix-dc-scm"
				(path ""
					(reference "R61")
					(unit 1)
				)
			)
		)
	)
	(symbol
		(lib_id "antmicroResistors0402:R_1k_0402")
		(at 260.35 157.48 0)
		(unit 1)
		(exclude_from_sim no)
		(in_bom yes)
		(on_board yes)
		(dnp no)
		(property "Reference" "R94"
			(at 262.89 154.94 0)
			(effects
				(font
					(size 1.27 1.27)
				)
			)
		)
		(property "Value" "R_1k_0402"
			(at 280.67 170.18 0)
			(effects
				(font
					(size 1.27 1.27)
					(thickness 0.15)
				)
				(justify left bottom)
				(hide yes)
			)
		)
		(property "Footprint" "antmicro-footprints:R_0402_1005Metric"
			(at 280.67 172.72 0)
			(effects
				(font
					(size 1.27 1.27)
					(thickness 0.15)
				)
				(justify left bottom)
				(hide yes)
			)
		)
		(property "Datasheet" "https://www.bourns.com/docs/product-datasheets/cr.pdf"
			(at 280.67 175.26 0)
			(effects
				(font
					(size 1.27 1.27)
					(thickness 0.15)
				)
				(justify left bottom)
				(hide yes)
			)
		)
		(property "Description" "SMD Chip Resistor, 1 kohm, ± 1%, 63 mW, 0402 [1005 Metric], Thick Film, General Purpose"
			(at 260.35 157.48 0)
			(effects
				(font
					(size 1.27 1.27)
				)
				(hide yes)
			)
		)
		(property "Manufacturer" "Bourns"
			(at 280.67 180.34 0)
			(effects
				(font
					(size 1.27 1.27)
					(thickness 0.15)
				)
				(justify left bottom)
				(hide yes)
			)
		)
		(property "MPN" "CR0402-FX-1001GLF"
			(at 280.67 177.8 0)
			(effects
				(font
					(size 1.27 1.27)
					(thickness 0.15)
				)
				(justify left bottom)
				(hide yes)
			)
		)
		(property "Val" "1k"
			(at 262.89 160.02 0)
			(effects
				(font
					(size 1.27 1.27)
					(thickness 0.15)
				)
			)
		)
		(property "License" "Apache-2.0"
			(at 280.67 182.88 0)
			(effects
				(font
					(size 1.27 1.27)
					(thickness 0.15)
				)
				(justify left bottom)
				(hide yes)
			)
		)
		(property "Author" "Antmicro"
			(at 280.67 185.42 0)
			(effects
				(font
					(size 1.27 1.27)
					(thickness 0.15)
				)
				(justify left bottom)
				(hide yes)
			)
		)
		(property "Tolerance" "1%"
			(at 280.67 167.64 0)
			(effects
				(font
					(size 1.27 1.27)
				)
				(justify left bottom)
				(hide yes)
			)
		)
		(pin "1"
		)
		(pin "2"
		)
		(instances
			(project "artix-dc-scm"
				(path ""
					(reference "R94")
					(unit 1)
				)
			)
		)
	)
	(symbol
		(lib_id "antmicropower:GND")
		(at 236.22 171.45 0)
		(unit 1)
		(exclude_from_sim no)
		(in_bom yes)
		(on_board yes)
		(dnp no)
		(property "Reference" "#PWR0106"
			(at 236.22 177.8 0)
			(effects
				(font
					(size 1.27 1.27)
				)
				(hide yes)
			)
		)
		(property "Value" "GND"
			(at 236.22 175.26 0)
			(effects
				(font
					(size 1.27 1.27)
				)
			)
		)
		(property "Footprint" ""
			(at 236.22 171.45 0)
			(effects
				(font
					(size 1.27 1.27)
				)
				(hide yes)
			)
		)
		(property "Datasheet" ""
			(at 236.22 171.45 0)
			(effects
				(font
					(size 1.27 1.27)
				)
				(hide yes)
			)
		)
		(property "Description" ""
			(at 236.22 171.45 0)
			(effects
				(font
					(size 1.27 1.27)
				)
				(hide yes)
			)
		)
		(property "Author" "Antmicro"
			(at 245.11 179.07 0)
			(effects
				(font
					(size 1.27 1.27)
					(thickness 0.15)
				)
				(justify left bottom)
				(hide yes)
			)
		)
		(property "License" "Apache-2.0"
			(at 245.11 181.61 0)
			(effects
				(font
					(size 1.27 1.27)
					(thickness 0.15)
				)
				(justify left bottom)
				(hide yes)
			)
		)
		(pin "1"
		)
		(instances
			(project "artix-dc-scm"
				(path ""
					(reference "#PWR0106")
					(unit 1)
				)
			)
		)
	)
	(symbol
		(lib_id "antmicroResistors0402:R_1k_0402")
		(at 260.35 187.96 0)
		(unit 1)
		(exclude_from_sim no)
		(in_bom yes)
		(on_board yes)
		(dnp no)
		(property "Reference" "R95"
			(at 262.89 185.42 0)
			(effects
				(font
					(size 1.27 1.27)
				)
			)
		)
		(property "Value" "R_1k_0402"
			(at 280.67 200.66 0)
			(effects
				(font
					(size 1.27 1.27)
					(thickness 0.15)
				)
				(justify left bottom)
				(hide yes)
			)
		)
		(property "Footprint" "antmicro-footprints:R_0402_1005Metric"
			(at 280.67 203.2 0)
			(effects
				(font
					(size 1.27 1.27)
					(thickness 0.15)
				)
				(justify left bottom)
				(hide yes)
			)
		)
		(property "Datasheet" "https://www.bourns.com/docs/product-datasheets/cr.pdf"
			(at 280.67 205.74 0)
			(effects
				(font
					(size 1.27 1.27)
					(thickness 0.15)
				)
				(justify left bottom)
				(hide yes)
			)
		)
		(property "Description" "SMD Chip Resistor, 1 kohm, ± 1%, 63 mW, 0402 [1005 Metric], Thick Film, General Purpose"
			(at 260.35 187.96 0)
			(effects
				(font
					(size 1.27 1.27)
				)
				(hide yes)
			)
		)
		(property "Manufacturer" "Bourns"
			(at 280.67 210.82 0)
			(effects
				(font
					(size 1.27 1.27)
					(thickness 0.15)
				)
				(justify left bottom)
				(hide yes)
			)
		)
		(property "MPN" "CR0402-FX-1001GLF"
			(at 280.67 208.28 0)
			(effects
				(font
					(size 1.27 1.27)
					(thickness 0.15)
				)
				(justify left bottom)
				(hide yes)
			)
		)
		(property "Val" "1k"
			(at 262.89 190.5 0)
			(effects
				(font
					(size 1.27 1.27)
					(thickness 0.15)
				)
			)
		)
		(property "License" "Apache-2.0"
			(at 280.67 213.36 0)
			(effects
				(font
					(size 1.27 1.27)
					(thickness 0.15)
				)
				(justify left bottom)
				(hide yes)
			)
		)
		(property "Author" "Antmicro"
			(at 280.67 215.9 0)
			(effects
				(font
					(size 1.27 1.27)
					(thickness 0.15)
				)
				(justify left bottom)
				(hide yes)
			)
		)
		(property "Tolerance" "1%"
			(at 280.67 198.12 0)
			(effects
				(font
					(size 1.27 1.27)
				)
				(justify left bottom)
				(hide yes)
			)
		)
		(pin "1"
		)
		(pin "2"
		)
		(instances
			(project "artix-dc-scm"
				(path ""
					(reference "R95")
					(unit 1)
				)
			)
		)
	)
	(symbol
		(lib_id "antmicropower:GND")
		(at 236.22 201.93 0)
		(unit 1)
		(exclude_from_sim no)
		(in_bom yes)
		(on_board yes)
		(dnp no)
		(property "Reference" "#PWR0107"
			(at 236.22 208.28 0)
			(effects
				(font
					(size 1.27 1.27)
				)
				(hide yes)
			)
		)
		(property "Value" "GND"
			(at 236.22 205.74 0)
			(effects
				(font
					(size 1.27 1.27)
				)
			)
		)
		(property "Footprint" ""
			(at 236.22 201.93 0)
			(effects
				(font
					(size 1.27 1.27)
				)
				(hide yes)
			)
		)
		(property "Datasheet" ""
			(at 236.22 201.93 0)
			(effects
				(font
					(size 1.27 1.27)
				)
				(hide yes)
			)
		)
		(property "Description" ""
			(at 236.22 201.93 0)
			(effects
				(font
					(size 1.27 1.27)
				)
				(hide yes)
			)
		)
		(property "Author" "Antmicro"
			(at 245.11 209.55 0)
			(effects
				(font
					(size 1.27 1.27)
					(thickness 0.15)
				)
				(justify left bottom)
				(hide yes)
			)
		)
		(property "License" "Apache-2.0"
			(at 245.11 212.09 0)
			(effects
				(font
					(size 1.27 1.27)
					(thickness 0.15)
				)
				(justify left bottom)
				(hide yes)
			)
		)
		(pin "1"
		)
		(instances
			(project "artix-dc-scm"
				(path ""
					(reference "#PWR0107")
					(unit 1)
				)
			)
		)
	)
	(symbol
		(lib_id "antmicroCapacitors0402:C_4n7_0402")
		(at 129.54 105.41 90)
		(unit 1)
		(exclude_from_sim no)
		(in_bom yes)
		(on_board yes)
		(dnp no)
		(property "Reference" "C68"
			(at 130.175 100.965 90)
			(effects
				(font
					(size 1.27 1.27)
				)
				(justify right)
			)
		)
		(property "Value" "C_4n7_0402"
			(at 139.7 85.09 0)
			(effects
				(font
					(size 1.27 1.27)
					(thickness 0.15)
				)
				(justify left bottom)
				(hide yes)
			)
		)
		(property "Footprint" "antmicro-footprints:C_0402_1005Metric"
			(at 142.24 85.09 0)
			(effects
				(font
					(size 1.27 1.27)
					(thickness 0.15)
				)
				(justify left bottom)
				(hide yes)
			)
		)
		(property "Datasheet" "https://product.tdk.com/en/search/capacitor/ceramic/mlcc/info?part_no=CGA2B3X7S2A472K050BB"
			(at 144.78 85.09 0)
			(effects
				(font
					(size 1.27 1.27)
					(thickness 0.15)
				)
				(justify left bottom)
				(hide yes)
			)
		)
		(property "Description" "SMD Multilayer Ceramic Capacitor, 4700 pF, 100 V, 0402 [1005 Metric], ± 10%, X7S, CGA"
			(at 129.54 105.41 0)
			(effects
				(font
					(size 1.27 1.27)
				)
				(hide yes)
			)
		)
		(property "Manufacturer" "TDK"
			(at 149.86 85.09 0)
			(effects
				(font
					(size 1.27 1.27)
					(thickness 0.15)
				)
				(justify left bottom)
				(hide yes)
			)
		)
		(property "MPN" "CGA2B3X7S2A472K050BB"
			(at 147.32 85.09 0)
			(effects
				(font
					(size 1.27 1.27)
					(thickness 0.15)
				)
				(justify left bottom)
				(hide yes)
			)
		)
		(property "Val" "4n7"
			(at 130.175 104.775 90)
			(effects
				(font
					(size 1.27 1.27)
					(thickness 0.15)
				)
				(justify right)
			)
		)
		(property "License" "Apache-2.0"
			(at 152.4 85.09 0)
			(effects
				(font
					(size 1.27 1.27)
					(thickness 0.15)
				)
				(justify left bottom)
				(hide yes)
			)
		)
		(property "Author" "Antmicro"
			(at 154.94 85.09 0)
			(effects
				(font
					(size 1.27 1.27)
					(thickness 0.15)
				)
				(justify left bottom)
				(hide yes)
			)
		)
		(property "Voltage" ""
			(at 157.48 85.09 0)
			(effects
				(font
					(size 1.27 1.27)
				)
				(justify left bottom)
				(hide yes)
			)
		)
		(property "Dielectric" ""
			(at 160.02 85.09 0)
			(effects
				(font
					(size 1.27 1.27)
				)
				(justify left bottom)
				(hide yes)
			)
		)
		(pin "1"
		)
		(pin "2"
		)
		(instances
			(project "artix-dc-scm"
				(path ""
					(reference "C68")
					(unit 1)
				)
			)
		)
	)
	(symbol
		(lib_id "antmicroCapacitors0402:C_47p_0402")
		(at 123.19 105.41 90)
		(unit 1)
		(exclude_from_sim no)
		(in_bom yes)
		(on_board yes)
		(dnp no)
		(property "Reference" "C70"
			(at 123.825 100.965 90)
			(effects
				(font
					(size 1.27 1.27)
				)
				(justify right)
			)
		)
		(property "Value" "C_47p_0402"
			(at 133.35 85.09 0)
			(effects
				(font
					(size 1.27 1.27)
					(thickness 0.15)
				)
				(justify left bottom)
				(hide yes)
			)
		)
		(property "Footprint" "antmicro-footprints:C_0402_1005Metric"
			(at 135.89 85.09 0)
			(effects
				(font
					(size 1.27 1.27)
					(thickness 0.15)
				)
				(justify left bottom)
				(hide yes)
			)
		)
		(property "Datasheet" "https://www.kemet.com/en/us/capacitors/product/C0402C470J5GACTU.html"
			(at 138.43 85.09 0)
			(effects
				(font
					(size 1.27 1.27)
					(thickness 0.15)
				)
				(justify left bottom)
				(hide yes)
			)
		)
		(property "Description" "SMD Multilayer Ceramic Capacitor, 47 pF, 50 V, 0402 [1005 Metric], ± 5%, C0G / NP0, C Series KEMET"
			(at 123.19 105.41 0)
			(effects
				(font
					(size 1.27 1.27)
				)
				(hide yes)
			)
		)
		(property "Manufacturer" "KEMET"
			(at 143.51 85.09 0)
			(effects
				(font
					(size 1.27 1.27)
					(thickness 0.15)
				)
				(justify left bottom)
				(hide yes)
			)
		)
		(property "MPN" "C0402C470J5GACTU"
			(at 140.97 85.09 0)
			(effects
				(font
					(size 1.27 1.27)
					(thickness 0.15)
				)
				(justify left bottom)
				(hide yes)
			)
		)
		(property "Val" "47p"
			(at 123.825 104.775 90)
			(effects
				(font
					(size 1.27 1.27)
					(thickness 0.15)
				)
				(justify right)
			)
		)
		(property "License" "Apache-2.0"
			(at 146.05 85.09 0)
			(effects
				(font
					(size 1.27 1.27)
					(thickness 0.15)
				)
				(justify left bottom)
				(hide yes)
			)
		)
		(property "Author" "Antmicro"
			(at 148.59 85.09 0)
			(effects
				(font
					(size 1.27 1.27)
					(thickness 0.15)
				)
				(justify left bottom)
				(hide yes)
			)
		)
		(property "Voltage" ""
			(at 151.13 85.09 0)
			(effects
				(font
					(size 1.27 1.27)
				)
				(justify left bottom)
				(hide yes)
			)
		)
		(property "Dielectric" "C0G"
			(at 153.67 85.09 0)
			(effects
				(font
					(size 1.27 1.27)
				)
				(justify left bottom)
				(hide yes)
			)
		)
		(pin "1"
		)
		(pin "2"
		)
		(instances
			(project "artix-dc-scm"
				(path ""
					(reference "C70")
					(unit 1)
				)
			)
		)
	)
	(symbol
		(lib_id "antmicropower:GND")
		(at 129.54 107.95 0)
		(mirror y)
		(unit 1)
		(exclude_from_sim no)
		(in_bom yes)
		(on_board yes)
		(dnp no)
		(property "Reference" "#PWR054"
			(at 129.54 114.3 0)
			(effects
				(font
					(size 1.27 1.27)
				)
				(hide yes)
			)
		)
		(property "Value" "GND"
			(at 129.54 111.76 0)
			(effects
				(font
					(size 1.27 1.27)
				)
			)
		)
		(property "Footprint" ""
			(at 129.54 107.95 0)
			(effects
				(font
					(size 1.27 1.27)
				)
				(hide yes)
			)
		)
		(property "Datasheet" ""
			(at 129.54 107.95 0)
			(effects
				(font
					(size 1.27 1.27)
				)
				(hide yes)
			)
		)
		(property "Description" ""
			(at 129.54 107.95 0)
			(effects
				(font
					(size 1.27 1.27)
				)
				(hide yes)
			)
		)
		(property "Author" "Antmicro"
			(at 120.65 115.57 0)
			(effects
				(font
					(size 1.27 1.27)
					(thickness 0.15)
				)
				(justify left bottom)
				(hide yes)
			)
		)
		(property "License" "Apache-2.0"
			(at 120.65 118.11 0)
			(effects
				(font
					(size 1.27 1.27)
					(thickness 0.15)
				)
				(justify left bottom)
				(hide yes)
			)
		)
		(pin "1"
		)
		(instances
			(project "artix-dc-scm"
				(path ""
					(reference "#PWR054")
					(unit 1)
				)
			)
		)
	)
	(symbol
		(lib_id "antmicroResistors0402:R_16k9_0402")
		(at 129.54 93.98 270)
		(unit 1)
		(exclude_from_sim no)
		(in_bom yes)
		(on_board yes)
		(dnp no)
		(property "Reference" "R66"
			(at 130.81 95.25 90)
			(effects
				(font
					(size 1.27 1.27)
				)
				(justify left)
			)
		)
		(property "Value" "R_16k9_0402"
			(at 116.84 114.3 0)
			(effects
				(font
					(size 1.27 1.27)
					(thickness 0.15)
				)
				(justify left bottom)
				(hide yes)
			)
		)
		(property "Footprint" "antmicro-footprints:R_0402_1005Metric"
			(at 114.3 114.3 0)
			(effects
				(font
					(size 1.27 1.27)
					(thickness 0.15)
				)
				(justify left bottom)
				(hide yes)
			)
		)
		(property "Datasheet" "https://www.bourns.com/docs/product-datasheets/cr.pdf"
			(at 111.76 114.3 0)
			(effects
				(font
					(size 1.27 1.27)
					(thickness 0.15)
				)
				(justify left bottom)
				(hide yes)
			)
		)
		(property "Description" "SMD Chip Resistor, Ceramic, 16.9 kohm, ± 1%, 62.5 mW, 0402 [1005 Metric], Thick Film"
			(at 129.54 93.98 0)
			(effects
				(font
					(size 1.27 1.27)
				)
				(hide yes)
			)
		)
		(property "Manufacturer" "Bourns"
			(at 106.68 114.3 0)
			(effects
				(font
					(size 1.27 1.27)
					(thickness 0.15)
				)
				(justify left bottom)
				(hide yes)
			)
		)
		(property "MPN" "CR0402-FX-1692GLF"
			(at 109.22 114.3 0)
			(effects
				(font
					(size 1.27 1.27)
					(thickness 0.15)
				)
				(justify left bottom)
				(hide yes)
			)
		)
		(property "Val" "16k9"
			(at 130.81 97.79 90)
			(effects
				(font
					(size 1.27 1.27)
					(thickness 0.15)
				)
				(justify left)
			)
		)
		(property "License" "Apache-2.0"
			(at 104.14 114.3 0)
			(effects
				(font
					(size 1.27 1.27)
					(thickness 0.15)
				)
				(justify left bottom)
				(hide yes)
			)
		)
		(property "Author" "Antmicro"
			(at 101.6 114.3 0)
			(effects
				(font
					(size 1.27 1.27)
					(thickness 0.15)
				)
				(justify left bottom)
				(hide yes)
			)
		)
		(property "Tolerance" "1%"
			(at 119.38 114.3 0)
			(effects
				(font
					(size 1.27 1.27)
				)
				(justify left bottom)
				(hide yes)
			)
		)
		(pin "1"
		)
		(pin "2"
		)
		(instances
			(project "artix-dc-scm"
				(path ""
					(reference "R66")
					(unit 1)
				)
			)
		)
	)
	(symbol
		(lib_id "antmicroCapacitorsmisc:C_100n_6V3_0402")
		(at 121.92 76.2 270)
		(unit 1)
		(exclude_from_sim no)
		(in_bom yes)
		(on_board yes)
		(dnp no)
		(property "Reference" "C71"
			(at 123.825 77.47 90)
			(effects
				(font
					(size 1.27 1.27)
				)
				(justify left)
			)
		)
		(property "Value" "C_100n_6V3_0402"
			(at 111.76 96.52 0)
			(effects
				(font
					(size 1.27 1.27)
					(thickness 0.15)
				)
				(justify left bottom)
				(hide yes)
			)
		)
		(property "Footprint" "antmicro-footprints:C_0402_1005Metric"
			(at 109.22 96.52 0)
			(effects
				(font
					(size 1.27 1.27)
					(thickness 0.15)
				)
				(justify left bottom)
				(hide yes)
			)
		)
		(property "Datasheet" "https://www.passivecomponent.com/wp-content/uploads/datasheet/WTC_MLCC_General_Purpose.pdf"
			(at 106.68 96.52 0)
			(effects
				(font
					(size 1.27 1.27)
					(thickness 0.15)
				)
				(justify left bottom)
				(hide yes)
			)
		)
		(property "Description" "SMT Multilayer Ceramic Capacitor, 0.1 µF, 6.3 V, 0402 [1005 Metric], ± 10%, X5R, Walsin MLCC"
			(at 121.92 76.2 0)
			(effects
				(font
					(size 1.27 1.27)
				)
				(hide yes)
			)
		)
		(property "Manufacturer" "Walsin"
			(at 101.6 96.52 0)
			(effects
				(font
					(size 1.27 1.27)
					(thickness 0.15)
				)
				(justify left bottom)
				(hide yes)
			)
		)
		(property "MPN" "0402X104K6R3CT"
			(at 104.14 96.52 0)
			(effects
				(font
					(size 1.27 1.27)
					(thickness 0.15)
				)
				(justify left bottom)
				(hide yes)
			)
		)
		(property "Val" "100n"
			(at 123.825 80.01 90)
			(effects
				(font
					(size 1.27 1.27)
					(thickness 0.15)
				)
				(justify left)
			)
		)
		(property "License" "Apache-2.0"
			(at 99.06 96.52 0)
			(effects
				(font
					(size 1.27 1.27)
					(thickness 0.15)
				)
				(justify left bottom)
				(hide yes)
			)
		)
		(property "Author" "Antmicro"
			(at 96.52 96.52 0)
			(effects
				(font
					(size 1.27 1.27)
					(thickness 0.15)
				)
				(justify left bottom)
				(hide yes)
			)
		)
		(property "Voltage" ""
			(at 93.98 96.52 0)
			(effects
				(font
					(size 1.27 1.27)
				)
				(justify left bottom)
				(hide yes)
			)
		)
		(property "Dielectric" ""
			(at 91.44 96.52 0)
			(effects
				(font
					(size 1.27 1.27)
				)
				(justify left bottom)
				(hide yes)
			)
		)
		(property "Public" "False"
			(at 88.9 96.52 0)
			(effects
				(font
					(size 1.27 1.27)
				)
				(justify left bottom)
				(hide yes)
			)
		)
		(pin "1"
		)
		(pin "2"
		)
		(instances
			(project "artix-dc-scm"
				(path ""
					(reference "C71")
					(unit 1)
				)
			)
		)
	)
	(symbol
		(lib_id "antmicropower:GND")
		(at 154.94 101.6 0)
		(unit 1)
		(exclude_from_sim no)
		(in_bom yes)
		(on_board yes)
		(dnp no)
		(property "Reference" "#PWR057"
			(at 154.94 107.95 0)
			(effects
				(font
					(size 1.27 1.27)
				)
				(hide yes)
			)
		)
		(property "Value" "GND"
			(at 154.94 105.41 0)
			(effects
				(font
					(size 1.27 1.27)
				)
			)
		)
		(property "Footprint" ""
			(at 154.94 101.6 0)
			(effects
				(font
					(size 1.27 1.27)
				)
				(hide yes)
			)
		)
		(property "Datasheet" ""
			(at 154.94 101.6 0)
			(effects
				(font
					(size 1.27 1.27)
				)
				(hide yes)
			)
		)
		(property "Description" ""
			(at 154.94 101.6 0)
			(effects
				(font
					(size 1.27 1.27)
				)
				(hide yes)
			)
		)
		(property "Author" "Antmicro"
			(at 163.83 109.22 0)
			(effects
				(font
					(size 1.27 1.27)
					(thickness 0.15)
				)
				(justify left bottom)
				(hide yes)
			)
		)
		(property "License" "Apache-2.0"
			(at 163.83 111.76 0)
			(effects
				(font
					(size 1.27 1.27)
					(thickness 0.15)
				)
				(justify left bottom)
				(hide yes)
			)
		)
		(pin "1"
		)
		(instances
			(project "artix-dc-scm"
				(path ""
					(reference "#PWR057")
					(unit 1)
				)
			)
		)
	)
	(symbol
		(lib_id "antmicropower:GND")
		(at 148.59 85.09 0)
		(unit 1)
		(exclude_from_sim no)
		(in_bom yes)
		(on_board yes)
		(dnp no)
		(fields_autoplaced yes)
		(property "Reference" "#PWR056"
			(at 148.59 91.44 0)
			(effects
				(font
					(size 1.27 1.27)
				)
				(hide yes)
			)
		)
		(property "Value" "GND"
			(at 148.59 89.535 0)
			(effects
				(font
					(size 1.27 1.27)
				)
			)
		)
		(property "Footprint" ""
			(at 148.59 85.09 0)
			(effects
				(font
					(size 1.27 1.27)
				)
				(hide yes)
			)
		)
		(property "Datasheet" ""
			(at 148.59 85.09 0)
			(effects
				(font
					(size 1.27 1.27)
				)
				(hide yes)
			)
		)
		(property "Description" ""
			(at 148.59 85.09 0)
			(effects
				(font
					(size 1.27 1.27)
				)
				(hide yes)
			)
		)
		(property "Author" "Antmicro"
			(at 157.48 92.71 0)
			(effects
				(font
					(size 1.27 1.27)
					(thickness 0.15)
				)
				(justify left bottom)
				(hide yes)
			)
		)
		(property "License" "Apache-2.0"
			(at 157.48 95.25 0)
			(effects
				(font
					(size 1.27 1.27)
					(thickness 0.15)
				)
				(justify left bottom)
				(hide yes)
			)
		)
		(pin "1"
		)
		(instances
			(project "artix-dc-scm"
				(path ""
					(reference "#PWR056")
					(unit 1)
				)
			)
		)
	)
	(symbol
		(lib_id "antmicroResistors0402:R_10k2_0402")
		(at 154.94 96.52 270)
		(unit 1)
		(exclude_from_sim no)
		(in_bom yes)
		(on_board yes)
		(dnp no)
		(property "Reference" "R72"
			(at 156.21 97.79 90)
			(effects
				(font
					(size 1.27 1.27)
				)
				(justify left)
			)
		)
		(property "Value" "R_10k2_0402"
			(at 142.24 116.84 0)
			(effects
				(font
					(size 1.27 1.27)
					(thickness 0.15)
				)
				(justify left bottom)
				(hide yes)
			)
		)
		(property "Footprint" "antmicro-footprints:R_0402_1005Metric"
			(at 139.7 116.84 0)
			(effects
				(font
					(size 1.27 1.27)
					(thickness 0.15)
				)
				(justify left bottom)
				(hide yes)
			)
		)
		(property "Datasheet" "https://www.bourns.com/docs/product-datasheets/cr.pdf"
			(at 137.16 116.84 0)
			(effects
				(font
					(size 1.27 1.27)
					(thickness 0.15)
				)
				(justify left bottom)
				(hide yes)
			)
		)
		(property "Description" "SMD Chip Resistor"
			(at 154.94 96.52 0)
			(effects
				(font
					(size 1.27 1.27)
				)
				(hide yes)
			)
		)
		(property "Manufacturer" "Bourns"
			(at 132.08 116.84 0)
			(effects
				(font
					(size 1.27 1.27)
					(thickness 0.15)
				)
				(justify left bottom)
				(hide yes)
			)
		)
		(property "MPN" "CR0402-FX-1022GLF"
			(at 134.62 116.84 0)
			(effects
				(font
					(size 1.27 1.27)
					(thickness 0.15)
				)
				(justify left bottom)
				(hide yes)
			)
		)
		(property "Val" "10k2"
			(at 156.21 100.33 90)
			(effects
				(font
					(size 1.27 1.27)
					(thickness 0.15)
				)
				(justify left)
			)
		)
		(property "License" "Apache-2.0"
			(at 129.54 116.84 0)
			(effects
				(font
					(size 1.27 1.27)
					(thickness 0.15)
				)
				(justify left bottom)
				(hide yes)
			)
		)
		(property "Author" "Antmicro"
			(at 127 116.84 0)
			(effects
				(font
					(size 1.27 1.27)
					(thickness 0.15)
				)
				(justify left bottom)
				(hide yes)
			)
		)
		(property "Tolerance" "1%"
			(at 144.78 116.84 0)
			(effects
				(font
					(size 1.27 1.27)
				)
				(justify left bottom)
				(hide yes)
			)
		)
		(pin "1"
		)
		(pin "2"
		)
		(instances
			(project "artix-dc-scm"
				(path ""
					(reference "R72")
					(unit 1)
				)
			)
		)
	)
	(symbol
		(lib_id "antmicroPMICPowerSequencers:LM3881")
		(at 82.55 194.31 0)
		(unit 1)
		(exclude_from_sim no)
		(in_bom yes)
		(on_board yes)
		(dnp no)
		(fields_autoplaced yes)
		(property "Reference" "U9"
			(at 90.805 187.325 0)
			(effects
				(font
					(size 1.27 1.27)
				)
			)
		)
		(property "Value" "LM3881"
			(at 113.03 201.93 0)
			(effects
				(font
					(size 1.27 1.27)
					(thickness 0.15)
				)
				(justify left bottom)
				(hide yes)
			)
		)
		(property "Footprint" "antmicro-footprints:VSSOP-8_3x3mm_P0.65mm"
			(at 113.03 204.47 0)
			(effects
				(font
					(size 1.27 1.27)
					(thickness 0.15)
				)
				(justify left bottom)
				(hide yes)
			)
		)
		(property "Datasheet" "http://www.ti.com/lit/ds/symlink/lm3881.pdf"
			(at 113.03 207.01 0)
			(effects
				(font
					(size 1.27 1.27)
					(thickness 0.15)
				)
				(justify left bottom)
				(hide yes)
			)
		)
		(property "Description" "Power Sequencer, 3-Monitors, 2.7V-5.5Vin,VSSOP-8"
			(at 82.55 194.31 0)
			(effects
				(font
					(size 1.27 1.27)
				)
				(hide yes)
			)
		)
		(property "Manufacturer" "Texas Instruments"
			(at 113.03 209.55 0)
			(effects
				(font
					(size 1.27 1.27)
					(thickness 0.15)
				)
				(justify left bottom)
				(hide yes)
			)
		)
		(property "MPN" "LM3881MME/NOPB"
			(at 90.805 189.865 0)
			(effects
				(font
					(size 1.27 1.27)
					(thickness 0.15)
				)
			)
		)
		(property "Author" "Antmicro"
			(at 113.03 212.09 0)
			(effects
				(font
					(size 1.27 1.27)
					(thickness 0.15)
				)
				(justify left bottom)
				(hide yes)
			)
		)
		(property "License" "Apache-2.0"
			(at 113.03 214.63 0)
			(effects
				(font
					(size 1.27 1.27)
					(thickness 0.15)
				)
				(justify left bottom)
				(hide yes)
			)
		)
		(pin "1"
		)
		(pin "2"
		)
		(pin "3"
		)
		(pin "4"
		)
		(pin "5"
		)
		(pin "6"
		)
		(pin "7"
		)
		(pin "8"
		)
		(instances
			(project "artix-dc-scm"
				(path ""
					(reference "U9")
					(unit 1)
				)
			)
		)
	)
	(symbol
		(lib_id "antmicroResistors0402:R_49R9_0402")
		(at 154.94 82.55 270)
		(unit 1)
		(exclude_from_sim no)
		(in_bom yes)
		(on_board yes)
		(dnp no)
		(property "Reference" "R70"
			(at 156.21 83.82 90)
			(effects
				(font
					(size 1.27 1.27)
				)
				(justify left)
			)
		)
		(property "Value" "R_49R9_0402"
			(at 142.24 102.87 0)
			(effects
				(font
					(size 1.27 1.27)
					(thickness 0.15)
				)
				(justify left bottom)
				(hide yes)
			)
		)
		(property "Footprint" "antmicro-footprints:R_0402_1005Metric"
			(at 139.7 102.87 0)
			(effects
				(font
					(size 1.27 1.27)
					(thickness 0.15)
				)
				(justify left bottom)
				(hide yes)
			)
		)
		(property "Datasheet" "https://www.bourns.com/docs/product-datasheets/cr.pdf"
			(at 137.16 102.87 0)
			(effects
				(font
					(size 1.27 1.27)
					(thickness 0.15)
				)
				(justify left bottom)
				(hide yes)
			)
		)
		(property "Description" "SMD Chip Resistor, 49.9 ohm, ± 1%, 62.5 mW, 0402 [1005 Metric], Thick Film, General Purpose"
			(at 154.94 82.55 0)
			(effects
				(font
					(size 1.27 1.27)
				)
				(hide yes)
			)
		)
		(property "Manufacturer" "Bourns"
			(at 132.08 102.87 0)
			(effects
				(font
					(size 1.27 1.27)
					(thickness 0.15)
				)
				(justify left bottom)
				(hide yes)
			)
		)
		(property "MPN" "CR0402-FX-49R9GLF"
			(at 134.62 102.87 0)
			(effects
				(font
					(size 1.27 1.27)
					(thickness 0.15)
				)
				(justify left bottom)
				(hide yes)
			)
		)
		(property "Val" "49R9"
			(at 156.21 86.36 90)
			(effects
				(font
					(size 1.27 1.27)
					(thickness 0.15)
				)
				(justify left)
			)
		)
		(property "License" "Apache-2.0"
			(at 129.54 102.87 0)
			(effects
				(font
					(size 1.27 1.27)
					(thickness 0.15)
				)
				(justify left bottom)
				(hide yes)
			)
		)
		(property "Author" "Antmicro"
			(at 127 102.87 0)
			(effects
				(font
					(size 1.27 1.27)
					(thickness 0.15)
				)
				(justify left bottom)
				(hide yes)
			)
		)
		(property "Tolerance" "1%"
			(at 144.78 102.87 0)
			(effects
				(font
					(size 1.27 1.27)
				)
				(justify left bottom)
				(hide yes)
			)
		)
		(pin "1"
		)
		(pin "2"
		)
		(instances
			(project "artix-dc-scm"
				(path ""
					(reference "R70")
					(unit 1)
				)
			)
		)
	)
	(symbol
		(lib_id "antmicroResistors0402:R_53k6_0402")
		(at 154.94 88.9 270)
		(unit 1)
		(exclude_from_sim no)
		(in_bom yes)
		(on_board yes)
		(dnp no)
		(property "Reference" "R71"
			(at 156.21 90.17 90)
			(effects
				(font
					(size 1.27 1.27)
				)
				(justify left)
			)
		)
		(property "Value" "R_53k6_0402"
			(at 142.24 109.22 0)
			(effects
				(font
					(size 1.27 1.27)
					(thickness 0.15)
				)
				(justify left bottom)
				(hide yes)
			)
		)
		(property "Footprint" "antmicro-footprints:R_0402_1005Metric"
			(at 139.7 109.22 0)
			(effects
				(font
					(size 1.27 1.27)
					(thickness 0.15)
				)
				(justify left bottom)
				(hide yes)
			)
		)
		(property "Datasheet" "https://www.bourns.com/docs/product-datasheets/cr.pdf"
			(at 137.16 109.22 0)
			(effects
				(font
					(size 1.27 1.27)
					(thickness 0.15)
				)
				(justify left bottom)
				(hide yes)
			)
		)
		(property "Description" "SMD Chip Resistor"
			(at 154.94 88.9 0)
			(effects
				(font
					(size 1.27 1.27)
				)
				(hide yes)
			)
		)
		(property "Manufacturer" "Bourns"
			(at 132.08 109.22 0)
			(effects
				(font
					(size 1.27 1.27)
					(thickness 0.15)
				)
				(justify left bottom)
				(hide yes)
			)
		)
		(property "MPN" "CR0402-FX-5362GLF"
			(at 134.62 109.22 0)
			(effects
				(font
					(size 1.27 1.27)
					(thickness 0.15)
				)
				(justify left bottom)
				(hide yes)
			)
		)
		(property "Val" "53k6"
			(at 156.21 92.71 90)
			(effects
				(font
					(size 1.27 1.27)
					(thickness 0.15)
				)
				(justify left)
			)
		)
		(property "License" "Apache-2.0"
			(at 129.54 109.22 0)
			(effects
				(font
					(size 1.27 1.27)
					(thickness 0.15)
				)
				(justify left bottom)
				(hide yes)
			)
		)
		(property "Author" "Antmicro"
			(at 127 109.22 0)
			(effects
				(font
					(size 1.27 1.27)
					(thickness 0.15)
				)
				(justify left bottom)
				(hide yes)
			)
		)
		(property "Tolerance" "1%"
			(at 144.78 109.22 0)
			(effects
				(font
					(size 1.27 1.27)
				)
				(justify left bottom)
				(hide yes)
			)
		)
		(pin "1"
		)
		(pin "2"
		)
		(instances
			(project "artix-dc-scm"
				(path ""
					(reference "R71")
					(unit 1)
				)
			)
		)
	)
	(symbol
		(lib_id "antmicroFixedInductors:L_7u2_7.9A_WE-PDF-1064")
		(at 139.7 81.28 0)
		(unit 1)
		(exclude_from_sim no)
		(in_bom yes)
		(on_board yes)
		(dnp no)
		(fields_autoplaced yes)
		(property "Reference" "L1"
			(at 142.24 75.565 0)
			(effects
				(font
					(size 1.27 1.27)
				)
			)
		)
		(property "Value" "L_7u2_7.9A_WE-PDF-1064"
			(at 153.67 83.82 0)
			(effects
				(font
					(size 1.27 1.27)
					(thickness 0.15)
				)
				(justify left bottom)
				(hide yes)
			)
		)
		(property "Footprint" "antmicro-footprints:L_WE-PDF-1064"
			(at 153.67 88.9 0)
			(effects
				(font
					(size 1.27 1.27)
					(thickness 0.15)
				)
				(justify left bottom)
				(hide yes)
			)
		)
		(property "Datasheet" "https://www.we-online.com/catalog/datasheet/7447798720.pdf"
			(at 153.67 91.44 0)
			(effects
				(font
					(size 1.27 1.27)
					(thickness 0.15)
				)
				(justify left bottom)
				(hide yes)
			)
		)
		(property "Description" "Power Inductor (SMD), 7.2 µH, 7.9 A, Shielded, 6 A, WE-PDF"
			(at 139.7 81.28 0)
			(effects
				(font
					(size 1.27 1.27)
				)
				(hide yes)
			)
		)
		(property "Manufacturer" "Würth Elektronik"
			(at 153.67 93.98 0)
			(effects
				(font
					(size 1.27 1.27)
					(thickness 0.15)
				)
				(justify left bottom)
				(hide yes)
			)
		)
		(property "MPN" "7447798720"
			(at 153.67 96.52 0)
			(effects
				(font
					(size 1.27 1.27)
					(thickness 0.15)
				)
				(justify left bottom)
				(hide yes)
			)
		)
		(property "Val" "7u2/7.9A"
			(at 142.24 78.105 0)
			(effects
				(font
					(size 1.27 1.27)
					(thickness 0.15)
				)
			)
		)
		(property "ISat" "6 A"
			(at 153.67 97.79 0)
			(effects
				(font
					(size 1.27 1.27)
				)
				(justify left)
				(hide yes)
			)
		)
		(property "IMax" "7.9 A"
			(at 153.67 101.6 0)
			(effects
				(font
					(size 1.27 1.27)
					(thickness 0.15)
				)
				(justify left bottom)
				(hide yes)
			)
		)
		(property "Size" "10.2x10.2"
			(at 153.67 104.14 0)
			(effects
				(font
					(size 1.27 1.27)
					(thickness 0.15)
				)
				(justify left bottom)
				(hide yes)
			)
		)
		(property "Author" "Antmicro"
			(at 153.67 106.68 0)
			(effects
				(font
					(size 1.27 1.27)
					(thickness 0.15)
				)
				(justify left bottom)
				(hide yes)
			)
		)
		(property "License" "Apache-2.0"
			(at 153.67 109.22 0)
			(effects
				(font
					(size 1.27 1.27)
					(thickness 0.15)
				)
				(justify left bottom)
				(hide yes)
			)
		)
		(pin "1"
		)
		(pin "2"
		)
		(instances
			(project "artix-dc-scm"
				(path ""
					(reference "L1")
					(unit 1)
				)
			)
		)
	)
	(symbol
		(lib_id "antmicroCapacitors0603:C_47u_0603")
		(at 165.1 87.63 90)
		(unit 1)
		(exclude_from_sim no)
		(in_bom yes)
		(on_board yes)
		(dnp no)
		(property "Reference" "C72"
			(at 165.735 83.185 90)
			(effects
				(font
					(size 1.27 1.27)
				)
				(justify right)
			)
		)
		(property "Value" "C_47u_0603"
			(at 175.26 67.31 0)
			(effects
				(font
					(size 1.27 1.27)
					(thickness 0.15)
				)
				(justify left bottom)
				(hide yes)
			)
		)
		(property "Footprint" "antmicro-footprints:C_0603_1608Metric"
			(at 177.8 67.31 0)
			(effects
				(font
					(size 1.27 1.27)
					(thickness 0.15)
				)
				(justify left bottom)
				(hide yes)
			)
		)
		(property "Datasheet" "https://www.murata.com/products/productdetail?partno=GRM188R60J476ME15%23"
			(at 180.34 67.31 0)
			(effects
				(font
					(size 1.27 1.27)
					(thickness 0.15)
				)
				(justify left bottom)
				(hide yes)
			)
		)
		(property "Description" "SMD Multilayer Ceramic Capacitor, 47 µF, 6.3 V, 0603 [1608 Metric], ± 20%, X5R, GRM Series"
			(at 165.1 87.63 0)
			(effects
				(font
					(size 1.27 1.27)
				)
				(hide yes)
			)
		)
		(property "Manufacturer" "Murata"
			(at 185.42 67.31 0)
			(effects
				(font
					(size 1.27 1.27)
					(thickness 0.15)
				)
				(justify left bottom)
				(hide yes)
			)
		)
		(property "MPN" "GRM188R60J476ME15D"
			(at 182.88 67.31 0)
			(effects
				(font
					(size 1.27 1.27)
					(thickness 0.15)
				)
				(justify left bottom)
				(hide yes)
			)
		)
		(property "Val" "47u"
			(at 165.735 86.995 90)
			(effects
				(font
					(size 1.27 1.27)
					(thickness 0.15)
				)
				(justify right)
			)
		)
		(property "License" "Apache-2.0"
			(at 187.96 67.31 0)
			(effects
				(font
					(size 1.27 1.27)
					(thickness 0.15)
				)
				(justify left bottom)
				(hide yes)
			)
		)
		(property "Author" "Antmicro"
			(at 190.5 67.31 0)
			(effects
				(font
					(size 1.27 1.27)
					(thickness 0.15)
				)
				(justify left bottom)
				(hide yes)
			)
		)
		(property "Voltage" ""
			(at 193.04 67.31 0)
			(effects
				(font
					(size 1.27 1.27)
				)
				(justify left bottom)
				(hide yes)
			)
		)
		(property "Dielectric" ""
			(at 195.58 67.31 0)
			(effects
				(font
					(size 1.27 1.27)
				)
				(justify left bottom)
				(hide yes)
			)
		)
		(pin "1"
		)
		(pin "2"
		)
		(instances
			(project "artix-dc-scm"
				(path ""
					(reference "C72")
					(unit 1)
				)
			)
		)
	)
	(symbol
		(lib_id "antmicroCapacitors0603:C_47u_0603")
		(at 171.45 87.63 90)
		(unit 1)
		(exclude_from_sim no)
		(in_bom yes)
		(on_board yes)
		(dnp no)
		(property "Reference" "C73"
			(at 172.085 83.185 90)
			(effects
				(font
					(size 1.27 1.27)
				)
				(justify right)
			)
		)
		(property "Value" "C_47u_0603"
			(at 181.61 67.31 0)
			(effects
				(font
					(size 1.27 1.27)
					(thickness 0.15)
				)
				(justify left bottom)
				(hide yes)
			)
		)
		(property "Footprint" "antmicro-footprints:C_0603_1608Metric"
			(at 184.15 67.31 0)
			(effects
				(font
					(size 1.27 1.27)
					(thickness 0.15)
				)
				(justify left bottom)
				(hide yes)
			)
		)
		(property "Datasheet" "https://www.murata.com/products/productdetail?partno=GRM188R60J476ME15%23"
			(at 186.69 67.31 0)
			(effects
				(font
					(size 1.27 1.27)
					(thickness 0.15)
				)
				(justify left bottom)
				(hide yes)
			)
		)
		(property "Description" "SMD Multilayer Ceramic Capacitor, 47 µF, 6.3 V, 0603 [1608 Metric], ± 20%, X5R, GRM Series"
			(at 171.45 87.63 0)
			(effects
				(font
					(size 1.27 1.27)
				)
				(hide yes)
			)
		)
		(property "Manufacturer" "Murata"
			(at 191.77 67.31 0)
			(effects
				(font
					(size 1.27 1.27)
					(thickness 0.15)
				)
				(justify left bottom)
				(hide yes)
			)
		)
		(property "MPN" "GRM188R60J476ME15D"
			(at 189.23 67.31 0)
			(effects
				(font
					(size 1.27 1.27)
					(thickness 0.15)
				)
				(justify left bottom)
				(hide yes)
			)
		)
		(property "Val" "47u"
			(at 172.085 86.995 90)
			(effects
				(font
					(size 1.27 1.27)
					(thickness 0.15)
				)
				(justify right)
			)
		)
		(property "License" "Apache-2.0"
			(at 194.31 67.31 0)
			(effects
				(font
					(size 1.27 1.27)
					(thickness 0.15)
				)
				(justify left bottom)
				(hide yes)
			)
		)
		(property "Author" "Antmicro"
			(at 196.85 67.31 0)
			(effects
				(font
					(size 1.27 1.27)
					(thickness 0.15)
				)
				(justify left bottom)
				(hide yes)
			)
		)
		(property "Voltage" ""
			(at 199.39 67.31 0)
			(effects
				(font
					(size 1.27 1.27)
				)
				(justify left bottom)
				(hide yes)
			)
		)
		(property "Dielectric" ""
			(at 201.93 67.31 0)
			(effects
				(font
					(size 1.27 1.27)
				)
				(justify left bottom)
				(hide yes)
			)
		)
		(pin "1"
		)
		(pin "2"
		)
		(instances
			(project "artix-dc-scm"
				(path ""
					(reference "C73")
					(unit 1)
				)
			)
		)
	)
	(symbol
		(lib_id "antmicroCapacitors0603:C_47u_0603")
		(at 177.8 87.63 90)
		(unit 1)
		(exclude_from_sim no)
		(in_bom yes)
		(on_board yes)
		(dnp no)
		(property "Reference" "C74"
			(at 178.435 83.185 90)
			(effects
				(font
					(size 1.27 1.27)
				)
				(justify right)
			)
		)
		(property "Value" "C_47u_0603"
			(at 187.96 67.31 0)
			(effects
				(font
					(size 1.27 1.27)
					(thickness 0.15)
				)
				(justify left bottom)
				(hide yes)
			)
		)
		(property "Footprint" "antmicro-footprints:C_0603_1608Metric"
			(at 190.5 67.31 0)
			(effects
				(font
					(size 1.27 1.27)
					(thickness 0.15)
				)
				(justify left bottom)
				(hide yes)
			)
		)
		(property "Datasheet" "https://www.murata.com/products/productdetail?partno=GRM188R60J476ME15%23"
			(at 193.04 67.31 0)
			(effects
				(font
					(size 1.27 1.27)
					(thickness 0.15)
				)
				(justify left bottom)
				(hide yes)
			)
		)
		(property "Description" "SMD Multilayer Ceramic Capacitor, 47 µF, 6.3 V, 0603 [1608 Metric], ± 20%, X5R, GRM Series"
			(at 177.8 87.63 0)
			(effects
				(font
					(size 1.27 1.27)
				)
				(hide yes)
			)
		)
		(property "Manufacturer" "Murata"
			(at 198.12 67.31 0)
			(effects
				(font
					(size 1.27 1.27)
					(thickness 0.15)
				)
				(justify left bottom)
				(hide yes)
			)
		)
		(property "MPN" "GRM188R60J476ME15D"
			(at 195.58 67.31 0)
			(effects
				(font
					(size 1.27 1.27)
					(thickness 0.15)
				)
				(justify left bottom)
				(hide yes)
			)
		)
		(property "Val" "47u"
			(at 178.435 86.995 90)
			(effects
				(font
					(size 1.27 1.27)
					(thickness 0.15)
				)
				(justify right)
			)
		)
		(property "License" "Apache-2.0"
			(at 200.66 67.31 0)
			(effects
				(font
					(size 1.27 1.27)
					(thickness 0.15)
				)
				(justify left bottom)
				(hide yes)
			)
		)
		(property "Author" "Antmicro"
			(at 203.2 67.31 0)
			(effects
				(font
					(size 1.27 1.27)
					(thickness 0.15)
				)
				(justify left bottom)
				(hide yes)
			)
		)
		(property "Voltage" ""
			(at 205.74 67.31 0)
			(effects
				(font
					(size 1.27 1.27)
				)
				(justify left bottom)
				(hide yes)
			)
		)
		(property "Dielectric" ""
			(at 208.28 67.31 0)
			(effects
				(font
					(size 1.27 1.27)
				)
				(justify left bottom)
				(hide yes)
			)
		)
		(pin "1"
		)
		(pin "2"
		)
		(instances
			(project "artix-dc-scm"
				(path ""
					(reference "C74")
					(unit 1)
				)
			)
		)
	)
	(symbol
		(lib_id "antmicropower:GND")
		(at 177.8 87.63 0)
		(unit 1)
		(exclude_from_sim no)
		(in_bom yes)
		(on_board yes)
		(dnp no)
		(property "Reference" "#PWR058"
			(at 177.8 93.98 0)
			(effects
				(font
					(size 1.27 1.27)
				)
				(hide yes)
			)
		)
		(property "Value" "GND"
			(at 177.8 91.44 0)
			(effects
				(font
					(size 1.27 1.27)
				)
			)
		)
		(property "Footprint" ""
			(at 177.8 87.63 0)
			(effects
				(font
					(size 1.27 1.27)
				)
				(hide yes)
			)
		)
		(property "Datasheet" ""
			(at 177.8 87.63 0)
			(effects
				(font
					(size 1.27 1.27)
				)
				(hide yes)
			)
		)
		(property "Description" ""
			(at 177.8 87.63 0)
			(effects
				(font
					(size 1.27 1.27)
				)
				(hide yes)
			)
		)
		(property "Author" "Antmicro"
			(at 186.69 95.25 0)
			(effects
				(font
					(size 1.27 1.27)
					(thickness 0.15)
				)
				(justify left bottom)
				(hide yes)
			)
		)
		(property "License" "Apache-2.0"
			(at 186.69 97.79 0)
			(effects
				(font
					(size 1.27 1.27)
					(thickness 0.15)
				)
				(justify left bottom)
				(hide yes)
			)
		)
		(pin "1"
		)
		(instances
			(project "artix-dc-scm"
				(path ""
					(reference "#PWR058")
					(unit 1)
				)
			)
		)
	)
	(symbol
		(lib_id "antmicroResistors0402:R_66k5_0402")
		(at 360.68 168.91 270)
		(unit 1)
		(exclude_from_sim no)
		(in_bom yes)
		(on_board yes)
		(dnp no)
		(property "Reference" "R77"
			(at 361.95 170.18 90)
			(effects
				(font
					(size 1.27 1.27)
				)
				(justify left)
			)
		)
		(property "Value" "R_66k5_0402"
			(at 347.98 189.23 0)
			(effects
				(font
					(size 1.27 1.27)
					(thickness 0.15)
				)
				(justify left bottom)
				(hide yes)
			)
		)
		(property "Footprint" "antmicro-footprints:R_0402_1005Metric"
			(at 345.44 189.23 0)
			(effects
				(font
					(size 1.27 1.27)
					(thickness 0.15)
				)
				(justify left bottom)
				(hide yes)
			)
		)
		(property "Datasheet" "https://www.bourns.com/docs/product-datasheets/cr.pdf"
			(at 342.9 189.23 0)
			(effects
				(font
					(size 1.27 1.27)
					(thickness 0.15)
				)
				(justify left bottom)
				(hide yes)
			)
		)
		(property "Description" "SMD Chip Resistor"
			(at 360.68 168.91 0)
			(effects
				(font
					(size 1.27 1.27)
				)
				(hide yes)
			)
		)
		(property "Manufacturer" "Bourns"
			(at 337.82 189.23 0)
			(effects
				(font
					(size 1.27 1.27)
					(thickness 0.15)
				)
				(justify left bottom)
				(hide yes)
			)
		)
		(property "MPN" "CR0402-FX-6652GLF"
			(at 340.36 189.23 0)
			(effects
				(font
					(size 1.27 1.27)
					(thickness 0.15)
				)
				(justify left bottom)
				(hide yes)
			)
		)
		(property "Val" "66k5"
			(at 361.95 172.72 90)
			(effects
				(font
					(size 1.27 1.27)
					(thickness 0.15)
				)
				(justify left)
			)
		)
		(property "License" "Apache-2.0"
			(at 335.28 189.23 0)
			(effects
				(font
					(size 1.27 1.27)
					(thickness 0.15)
				)
				(justify left bottom)
				(hide yes)
			)
		)
		(property "Author" "Antmicro"
			(at 332.74 189.23 0)
			(effects
				(font
					(size 1.27 1.27)
					(thickness 0.15)
				)
				(justify left bottom)
				(hide yes)
			)
		)
		(property "Tolerance" "1%"
			(at 350.52 189.23 0)
			(effects
				(font
					(size 1.27 1.27)
				)
				(justify left bottom)
				(hide yes)
			)
		)
		(pin "1"
		)
		(pin "2"
		)
		(instances
			(project "artix-dc-scm"
				(path ""
					(reference "R77")
					(unit 1)
				)
			)
		)
	)
	(symbol
		(lib_id "antmicroCapacitors0603:C_10u_0603")
		(at 316.23 30.48 90)
		(unit 1)
		(exclude_from_sim no)
		(in_bom yes)
		(on_board yes)
		(dnp no)
		(property "Reference" "C75"
			(at 316.865 26.035 90)
			(effects
				(font
					(size 1.27 1.27)
				)
				(justify right)
			)
		)
		(property "Value" "C_10u_0603"
			(at 326.39 10.16 0)
			(effects
				(font
					(size 1.27 1.27)
					(thickness 0.15)
				)
				(justify left bottom)
				(hide yes)
			)
		)
		(property "Footprint" "antmicro-footprints:C_0603_1608Metric"
			(at 328.93 10.16 0)
			(effects
				(font
					(size 1.27 1.27)
					(thickness 0.15)
				)
				(justify left bottom)
				(hide yes)
			)
		)
		(property "Datasheet" "https://www.murata.com/products/productdetail?partno=GRM188R61A106KE69%23"
			(at 331.47 10.16 0)
			(effects
				(font
					(size 1.27 1.27)
					(thickness 0.15)
				)
				(justify left bottom)
				(hide yes)
			)
		)
		(property "Description" "SMD Multilayer Ceramic Capacitor, 10 µF, 10 V, 0603 [1608 Metric], ± 10%, X5R, GRM Series"
			(at 316.23 30.48 0)
			(effects
				(font
					(size 1.27 1.27)
				)
				(hide yes)
			)
		)
		(property "Manufacturer" "Murata"
			(at 336.55 10.16 0)
			(effects
				(font
					(size 1.27 1.27)
					(thickness 0.15)
				)
				(justify left bottom)
				(hide yes)
			)
		)
		(property "MPN" "GRM188R61A106KE69D"
			(at 334.01 10.16 0)
			(effects
				(font
					(size 1.27 1.27)
					(thickness 0.15)
				)
				(justify left bottom)
				(hide yes)
			)
		)
		(property "Val" "10u"
			(at 316.865 29.845 90)
			(effects
				(font
					(size 1.27 1.27)
					(thickness 0.15)
				)
				(justify right)
			)
		)
		(property "License" "Apache-2.0"
			(at 339.09 10.16 0)
			(effects
				(font
					(size 1.27 1.27)
					(thickness 0.15)
				)
				(justify left bottom)
				(hide yes)
			)
		)
		(property "Author" "Antmicro"
			(at 341.63 10.16 0)
			(effects
				(font
					(size 1.27 1.27)
					(thickness 0.15)
				)
				(justify left bottom)
				(hide yes)
			)
		)
		(property "Voltage" ""
			(at 344.17 10.16 0)
			(effects
				(font
					(size 1.27 1.27)
				)
				(justify left bottom)
				(hide yes)
			)
		)
		(property "Dielectric" "template_dielectric"
			(at 346.71 10.16 0)
			(effects
				(font
					(size 1.27 1.27)
				)
				(justify left bottom)
				(hide yes)
			)
		)
		(pin "1"
		)
		(pin "2"
		)
		(instances
			(project "artix-dc-scm"
				(path ""
					(reference "C75")
					(unit 1)
				)
			)
		)
	)
	(symbol
		(lib_id "antmicroCapacitors0603:C_10u_25V_0603")
		(at 44.45 63.5 90)
		(unit 1)
		(exclude_from_sim no)
		(in_bom yes)
		(on_board yes)
		(dnp no)
		(property "Reference" "C14"
			(at 45.085 59.055 90)
			(effects
				(font
					(size 1.27 1.27)
				)
				(justify right)
			)
		)
		(property "Value" "C_10u_25V_0603"
			(at 54.61 43.18 0)
			(effects
				(font
					(size 1.27 1.27)
					(thickness 0.15)
				)
				(justify left bottom)
				(hide yes)
			)
		)
		(property "Footprint" "antmicro-footprints:C_0603_1608Metric"
			(at 57.15 43.18 0)
			(effects
				(font
					(size 1.27 1.27)
					(thickness 0.15)
				)
				(justify left bottom)
				(hide yes)
			)
		)
		(property "Datasheet" "https://product.tdk.com/en/search/capacitor/ceramic/mlcc/info?part_no=C1608X5R1E106M080AC"
			(at 59.69 43.18 0)
			(effects
				(font
					(size 1.27 1.27)
					(thickness 0.15)
				)
				(justify left bottom)
				(hide yes)
			)
		)
		(property "Description" "SMD Multilayer Ceramic Capacitor, 10 µF, 25 V, 0603 [1608 Metric], ± 20%, X5R, C"
			(at 44.45 63.5 0)
			(effects
				(font
					(size 1.27 1.27)
				)
				(hide yes)
			)
		)
		(property "Manufacturer" "TDK"
			(at 64.77 43.18 0)
			(effects
				(font
					(size 1.27 1.27)
					(thickness 0.15)
				)
				(justify left bottom)
				(hide yes)
			)
		)
		(property "MPN" "C1608X5R1E106M080AC"
			(at 62.23 43.18 0)
			(effects
				(font
					(size 1.27 1.27)
					(thickness 0.15)
				)
				(justify left bottom)
				(hide yes)
			)
		)
		(property "Val" "10u"
			(at 45.085 62.865 90)
			(effects
				(font
					(size 1.27 1.27)
					(thickness 0.15)
				)
				(justify right)
			)
		)
		(property "License" "Apache-2.0"
			(at 67.31 43.18 0)
			(effects
				(font
					(size 1.27 1.27)
					(thickness 0.15)
				)
				(justify left bottom)
				(hide yes)
			)
		)
		(property "Author" "Antmicro"
			(at 69.85 43.18 0)
			(effects
				(font
					(size 1.27 1.27)
					(thickness 0.15)
				)
				(justify left bottom)
				(hide yes)
			)
		)
		(property "Voltage" "25V"
			(at 72.39 43.18 0)
			(effects
				(font
					(size 1.27 1.27)
				)
				(justify left bottom)
				(hide yes)
			)
		)
		(property "Dielectric" ""
			(at 74.93 43.18 0)
			(effects
				(font
					(size 1.27 1.27)
				)
				(justify left bottom)
				(hide yes)
			)
		)
		(pin "1"
		)
		(pin "2"
		)
		(instances
			(project "artix-dc-scm"
				(path ""
					(reference "C14")
					(unit 1)
				)
			)
		)
	)
	(symbol
		(lib_id "antmicroDCDCConverters:TPS62823DLCT")
		(at 323.85 34.29 0)
		(unit 1)
		(exclude_from_sim no)
		(in_bom yes)
		(on_board yes)
		(dnp no)
		(property "Reference" "U10"
			(at 334.01 27.94 0)
			(effects
				(font
					(size 1.27 1.27)
				)
			)
		)
		(property "Value" "TPS62823DLCT"
			(at 334.01 30.48 0)
			(effects
				(font
					(size 1.27 1.27)
				)
			)
		)
		(property "Footprint" "antmicro-footprints:QFN-8_2x1.5mm"
			(at 358.14 38.1 0)
			(effects
				(font
					(size 1.27 1.27)
					(thickness 0.15)
				)
				(justify left bottom)
				(hide yes)
			)
		)
		(property "Datasheet" "https://www.ti.com/lit/ds/symlink/tps62823.pdf?ts=1685970309606&ref_url=https%253A%252F%252Fwww.ti.com%252Fproduct%252FTPS62823%252Fpart-details%252FTPS62823DLCT"
			(at 358.14 40.64 0)
			(effects
				(font
					(size 1.27 1.27)
					(thickness 0.15)
				)
				(justify left bottom)
				(hide yes)
			)
		)
		(property "Description" "DC/DC converter"
			(at 323.85 34.29 0)
			(effects
				(font
					(size 1.27 1.27)
				)
				(hide yes)
			)
		)
		(property "MPN" "TPS62823DLCT"
			(at 358.14 43.18 0)
			(effects
				(font
					(size 1.27 1.27)
					(thickness 0.15)
				)
				(justify left bottom)
				(hide yes)
			)
		)
		(property "Manufacturer" "Texas Instruments"
			(at 358.14 45.72 0)
			(effects
				(font
					(size 1.27 1.27)
					(thickness 0.15)
				)
				(justify left bottom)
				(hide yes)
			)
		)
		(property "Author" "Antmicro"
			(at 358.14 48.26 0)
			(effects
				(font
					(size 1.27 1.27)
					(thickness 0.15)
				)
				(justify left bottom)
				(hide yes)
			)
		)
		(property "License" "Apache-2.0"
			(at 358.14 50.8 0)
			(effects
				(font
					(size 1.27 1.27)
					(thickness 0.15)
				)
				(justify left bottom)
				(hide yes)
			)
		)
		(pin "4"
		)
		(pin "1"
		)
		(pin "2"
		)
		(pin "3"
		)
		(pin "5"
		)
		(pin "6"
		)
		(pin "7"
		)
		(pin "8"
		)
		(instances
			(project "artix-dc-scm"
				(path ""
					(reference "U10")
					(unit 1)
				)
			)
		)
	)
	(symbol
		(lib_id "antmicroCapacitors0603:C_10u_25V_0603")
		(at 54.61 63.5 90)
		(unit 1)
		(exclude_from_sim no)
		(in_bom yes)
		(on_board yes)
		(dnp no)
		(property "Reference" "C15"
			(at 55.245 59.055 90)
			(effects
				(font
					(size 1.27 1.27)
				)
				(justify right)
			)
		)
		(property "Value" "C_10u_25V_0603"
			(at 64.77 43.18 0)
			(effects
				(font
					(size 1.27 1.27)
					(thickness 0.15)
				)
				(justify left bottom)
				(hide yes)
			)
		)
		(property "Footprint" "antmicro-footprints:C_0603_1608Metric"
			(at 67.31 43.18 0)
			(effects
				(font
					(size 1.27 1.27)
					(thickness 0.15)
				)
				(justify left bottom)
				(hide yes)
			)
		)
		(property "Datasheet" "https://product.tdk.com/en/search/capacitor/ceramic/mlcc/info?part_no=C1608X5R1E106M080AC"
			(at 69.85 43.18 0)
			(effects
				(font
					(size 1.27 1.27)
					(thickness 0.15)
				)
				(justify left bottom)
				(hide yes)
			)
		)
		(property "Description" "SMD Multilayer Ceramic Capacitor, 10 µF, 25 V, 0603 [1608 Metric], ± 20%, X5R, C"
			(at 54.61 63.5 0)
			(effects
				(font
					(size 1.27 1.27)
				)
				(hide yes)
			)
		)
		(property "Manufacturer" "TDK"
			(at 74.93 43.18 0)
			(effects
				(font
					(size 1.27 1.27)
					(thickness 0.15)
				)
				(justify left bottom)
				(hide yes)
			)
		)
		(property "MPN" "C1608X5R1E106M080AC"
			(at 72.39 43.18 0)
			(effects
				(font
					(size 1.27 1.27)
					(thickness 0.15)
				)
				(justify left bottom)
				(hide yes)
			)
		)
		(property "Val" "10u"
			(at 55.245 62.865 90)
			(effects
				(font
					(size 1.27 1.27)
					(thickness 0.15)
				)
				(justify right)
			)
		)
		(property "License" "Apache-2.0"
			(at 77.47 43.18 0)
			(effects
				(font
					(size 1.27 1.27)
					(thickness 0.15)
				)
				(justify left bottom)
				(hide yes)
			)
		)
		(property "Author" "Antmicro"
			(at 80.01 43.18 0)
			(effects
				(font
					(size 1.27 1.27)
					(thickness 0.15)
				)
				(justify left bottom)
				(hide yes)
			)
		)
		(property "Voltage" "25V"
			(at 82.55 43.18 0)
			(effects
				(font
					(size 1.27 1.27)
				)
				(justify left bottom)
				(hide yes)
			)
		)
		(property "Dielectric" ""
			(at 85.09 43.18 0)
			(effects
				(font
					(size 1.27 1.27)
				)
				(justify left bottom)
				(hide yes)
			)
		)
		(pin "1"
		)
		(pin "2"
		)
		(instances
			(project "artix-dc-scm"
				(path ""
					(reference "C15")
					(unit 1)
				)
			)
		)
	)
	(symbol
		(lib_id "antmicroCapacitors0603:C_10u_25V_0603")
		(at 64.77 63.5 90)
		(unit 1)
		(exclude_from_sim no)
		(in_bom yes)
		(on_board yes)
		(dnp no)
		(property "Reference" "C16"
			(at 65.405 59.055 90)
			(effects
				(font
					(size 1.27 1.27)
				)
				(justify right)
			)
		)
		(property "Value" "C_10u_25V_0603"
			(at 74.93 43.18 0)
			(effects
				(font
					(size 1.27 1.27)
					(thickness 0.15)
				)
				(justify left bottom)
				(hide yes)
			)
		)
		(property "Footprint" "antmicro-footprints:C_0603_1608Metric"
			(at 77.47 43.18 0)
			(effects
				(font
					(size 1.27 1.27)
					(thickness 0.15)
				)
				(justify left bottom)
				(hide yes)
			)
		)
		(property "Datasheet" "https://product.tdk.com/en/search/capacitor/ceramic/mlcc/info?part_no=C1608X5R1E106M080AC"
			(at 80.01 43.18 0)
			(effects
				(font
					(size 1.27 1.27)
					(thickness 0.15)
				)
				(justify left bottom)
				(hide yes)
			)
		)
		(property "Description" "SMD Multilayer Ceramic Capacitor, 10 µF, 25 V, 0603 [1608 Metric], ± 20%, X5R, C"
			(at 64.77 63.5 0)
			(effects
				(font
					(size 1.27 1.27)
				)
				(hide yes)
			)
		)
		(property "Manufacturer" "TDK"
			(at 85.09 43.18 0)
			(effects
				(font
					(size 1.27 1.27)
					(thickness 0.15)
				)
				(justify left bottom)
				(hide yes)
			)
		)
		(property "MPN" "C1608X5R1E106M080AC"
			(at 82.55 43.18 0)
			(effects
				(font
					(size 1.27 1.27)
					(thickness 0.15)
				)
				(justify left bottom)
				(hide yes)
			)
		)
		(property "Val" "10u"
			(at 65.405 62.865 90)
			(effects
				(font
					(size 1.27 1.27)
					(thickness 0.15)
				)
				(justify right)
			)
		)
		(property "License" "Apache-2.0"
			(at 87.63 43.18 0)
			(effects
				(font
					(size 1.27 1.27)
					(thickness 0.15)
				)
				(justify left bottom)
				(hide yes)
			)
		)
		(property "Author" "Antmicro"
			(at 90.17 43.18 0)
			(effects
				(font
					(size 1.27 1.27)
					(thickness 0.15)
				)
				(justify left bottom)
				(hide yes)
			)
		)
		(property "Voltage" "25V"
			(at 92.71 43.18 0)
			(effects
				(font
					(size 1.27 1.27)
				)
				(justify left bottom)
				(hide yes)
			)
		)
		(property "Dielectric" ""
			(at 95.25 43.18 0)
			(effects
				(font
					(size 1.27 1.27)
				)
				(justify left bottom)
				(hide yes)
			)
		)
		(pin "1"
		)
		(pin "2"
		)
		(instances
			(project "artix-dc-scm"
				(path ""
					(reference "C16")
					(unit 1)
				)
			)
		)
	)
	(symbol
		(lib_id "antmicroCapacitors0402:C_120p_100V_0402")
		(at 353.06 40.64 90)
		(unit 1)
		(exclude_from_sim no)
		(in_bom yes)
		(on_board yes)
		(dnp no)
		(property "Reference" "C79"
			(at 353.695 36.195 90)
			(effects
				(font
					(size 1.27 1.27)
				)
				(justify right)
			)
		)
		(property "Value" "C_120p_0402"
			(at 363.22 20.32 0)
			(effects
				(font
					(size 1.27 1.27)
					(thickness 0.15)
				)
				(justify left bottom)
				(hide yes)
			)
		)
		(property "Footprint" "antmicro-footprints:C_0402_1005Metric"
			(at 365.76 20.32 0)
			(effects
				(font
					(size 1.27 1.27)
					(thickness 0.15)
				)
				(justify left bottom)
				(hide yes)
			)
		)
		(property "Datasheet" "https://www.kemet.com/en/us/capacitors/product/C0402C121J5GACTU.html"
			(at 368.3 20.32 0)
			(effects
				(font
					(size 1.27 1.27)
					(thickness 0.15)
				)
				(justify left bottom)
				(hide yes)
			)
		)
		(property "Description" "120 pF ±2% 100V Ceramic Capacitor C0G, NP0 0402 (1005 Metric)"
			(at 353.06 40.64 0)
			(effects
				(font
					(size 1.27 1.27)
				)
				(hide yes)
			)
		)
		(property "Manufacturer" "KEMET"
			(at 373.38 20.32 0)
			(effects
				(font
					(size 1.27 1.27)
					(thickness 0.15)
				)
				(justify left bottom)
				(hide yes)
			)
		)
		(property "MPN" "C0402C121J5GACTU"
			(at 370.84 20.32 0)
			(effects
				(font
					(size 1.27 1.27)
					(thickness 0.15)
				)
				(justify left bottom)
				(hide yes)
			)
		)
		(property "Val" "120p"
			(at 353.695 40.005 90)
			(effects
				(font
					(size 1.27 1.27)
					(thickness 0.15)
				)
				(justify right)
			)
		)
		(property "License" "Apache-2.0"
			(at 375.92 20.32 0)
			(effects
				(font
					(size 1.27 1.27)
					(thickness 0.15)
				)
				(justify left bottom)
				(hide yes)
			)
		)
		(property "Author" "Antmicro"
			(at 378.46 20.32 0)
			(effects
				(font
					(size 1.27 1.27)
					(thickness 0.15)
				)
				(justify left bottom)
				(hide yes)
			)
		)
		(property "Voltage" "100V"
			(at 381 20.32 0)
			(effects
				(font
					(size 1.27 1.27)
				)
				(justify left bottom)
				(hide yes)
			)
		)
		(property "Dielectric" "C0G"
			(at 383.54 20.32 0)
			(effects
				(font
					(size 1.27 1.27)
				)
				(justify left bottom)
				(hide yes)
			)
		)
		(pin "1"
		)
		(pin "2"
		)
		(instances
			(project "artix-dc-scm"
				(path ""
					(reference "C79")
					(unit 1)
				)
			)
		)
	)
	(symbol
		(lib_id "antmicroResistors0402:R_453k_0402")
		(at 360.68 35.56 270)
		(unit 1)
		(exclude_from_sim no)
		(in_bom yes)
		(on_board yes)
		(dnp no)
		(property "Reference" "R73"
			(at 361.95 36.83 90)
			(effects
				(font
					(size 1.27 1.27)
				)
				(justify left)
			)
		)
		(property "Value" "R_453k_0402"
			(at 347.98 55.88 0)
			(effects
				(font
					(size 1.27 1.27)
					(thickness 0.15)
				)
				(justify left bottom)
				(hide yes)
			)
		)
		(property "Footprint" "antmicro-footprints:R_0402_1005Metric"
			(at 345.44 55.88 0)
			(effects
				(font
					(size 1.27 1.27)
					(thickness 0.15)
				)
				(justify left bottom)
				(hide yes)
			)
		)
		(property "Datasheet" "https://www.bourns.com/docs/product-datasheets/cr.pdf"
			(at 342.9 55.88 0)
			(effects
				(font
					(size 1.27 1.27)
					(thickness 0.15)
				)
				(justify left bottom)
				(hide yes)
			)
		)
		(property "Description" "SMD Chip Resistor"
			(at 360.68 35.56 0)
			(effects
				(font
					(size 1.27 1.27)
				)
				(hide yes)
			)
		)
		(property "Manufacturer" "Bourns"
			(at 337.82 55.88 0)
			(effects
				(font
					(size 1.27 1.27)
					(thickness 0.15)
				)
				(justify left bottom)
				(hide yes)
			)
		)
		(property "MPN" "CR0402-FX-4533GLF"
			(at 340.36 55.88 0)
			(effects
				(font
					(size 1.27 1.27)
					(thickness 0.15)
				)
				(justify left bottom)
				(hide yes)
			)
		)
		(property "Val" "453k"
			(at 361.95 39.37 90)
			(effects
				(font
					(size 1.27 1.27)
					(thickness 0.15)
				)
				(justify left)
			)
		)
		(property "License" "Apache-2.0"
			(at 335.28 55.88 0)
			(effects
				(font
					(size 1.27 1.27)
					(thickness 0.15)
				)
				(justify left bottom)
				(hide yes)
			)
		)
		(property "Author" "Antmicro"
			(at 332.74 55.88 0)
			(effects
				(font
					(size 1.27 1.27)
					(thickness 0.15)
				)
				(justify left bottom)
				(hide yes)
			)
		)
		(property "Tolerance" "1%"
			(at 350.52 55.88 0)
			(effects
				(font
					(size 1.27 1.27)
				)
				(justify left bottom)
				(hide yes)
			)
		)
		(pin "1"
		)
		(pin "2"
		)
		(instances
			(project "artix-dc-scm"
				(path ""
					(reference "R73")
					(unit 1)
				)
			)
		)
	)
	(symbol
		(lib_id "antmicroResistors0402:R_100k_0402")
		(at 360.68 43.18 270)
		(unit 1)
		(exclude_from_sim no)
		(in_bom yes)
		(on_board yes)
		(dnp no)
		(property "Reference" "R74"
			(at 361.95 44.45 90)
			(effects
				(font
					(size 1.27 1.27)
				)
				(justify left)
			)
		)
		(property "Value" "R_100k_0402"
			(at 347.98 63.5 0)
			(effects
				(font
					(size 1.27 1.27)
					(thickness 0.15)
				)
				(justify left bottom)
				(hide yes)
			)
		)
		(property "Footprint" "antmicro-footprints:R_0402_1005Metric"
			(at 345.44 63.5 0)
			(effects
				(font
					(size 1.27 1.27)
					(thickness 0.15)
				)
				(justify left bottom)
				(hide yes)
			)
		)
		(property "Datasheet" "https://www.bourns.com/docs/product-datasheets/cr.pdf"
			(at 342.9 63.5 0)
			(effects
				(font
					(size 1.27 1.27)
					(thickness 0.15)
				)
				(justify left bottom)
				(hide yes)
			)
		)
		(property "Description" "SMD Chip Resistor, 100 kohm, ± 1%, 62.5 mW, 0402 [1005 Metric], Thick Film, General Purpose"
			(at 360.68 43.18 0)
			(effects
				(font
					(size 1.27 1.27)
				)
				(hide yes)
			)
		)
		(property "Manufacturer" "Bourns"
			(at 337.82 63.5 0)
			(effects
				(font
					(size 1.27 1.27)
					(thickness 0.15)
				)
				(justify left bottom)
				(hide yes)
			)
		)
		(property "MPN" "CR0402-FX-1003GLF"
			(at 340.36 63.5 0)
			(effects
				(font
					(size 1.27 1.27)
					(thickness 0.15)
				)
				(justify left bottom)
				(hide yes)
			)
		)
		(property "Val" "100k"
			(at 361.95 46.99 90)
			(effects
				(font
					(size 1.27 1.27)
					(thickness 0.15)
				)
				(justify left)
			)
		)
		(property "License" "Apache-2.0"
			(at 335.28 63.5 0)
			(effects
				(font
					(size 1.27 1.27)
					(thickness 0.15)
				)
				(justify left bottom)
				(hide yes)
			)
		)
		(property "Author" "Antmicro"
			(at 332.74 63.5 0)
			(effects
				(font
					(size 1.27 1.27)
					(thickness 0.15)
				)
				(justify left bottom)
				(hide yes)
			)
		)
		(property "Tolerance" "1%"
			(at 350.52 63.5 0)
			(effects
				(font
					(size 1.27 1.27)
				)
				(justify left bottom)
				(hide yes)
			)
		)
		(pin "1"
		)
		(pin "2"
		)
		(instances
			(project "artix-dc-scm"
				(path ""
					(reference "R74")
					(unit 1)
				)
			)
		)
	)
	(symbol
		(lib_id "antmicroCapacitors0402:C_10n_0402")
		(at 72.39 208.28 90)
		(unit 1)
		(exclude_from_sim no)
		(in_bom yes)
		(on_board yes)
		(dnp no)
		(property "Reference" "C64"
			(at 73.025 203.835 90)
			(effects
				(font
					(size 1.27 1.27)
				)
				(justify right)
			)
		)
		(property "Value" "C_10n_0402"
			(at 82.55 187.96 0)
			(effects
				(font
					(size 1.27 1.27)
					(thickness 0.15)
				)
				(justify left bottom)
				(hide yes)
			)
		)
		(property "Footprint" "antmicro-footprints:C_0402_1005Metric"
			(at 85.09 187.96 0)
			(effects
				(font
					(size 1.27 1.27)
					(thickness 0.15)
				)
				(justify left bottom)
				(hide yes)
			)
		)
		(property "Datasheet" "https://www.murata.com/products/productdetail?partno=GRM155R71H103KA88%23"
			(at 87.63 187.96 0)
			(effects
				(font
					(size 1.27 1.27)
					(thickness 0.15)
				)
				(justify left bottom)
				(hide yes)
			)
		)
		(property "Description" "SMD Multilayer Ceramic Capacitor, 10000 pF, 50 V, 0402 [1005 Metric], ± 10%, X7R, GRM Series"
			(at 72.39 208.28 0)
			(effects
				(font
					(size 1.27 1.27)
				)
				(hide yes)
			)
		)
		(property "Manufacturer" "Murata"
			(at 92.71 187.96 0)
			(effects
				(font
					(size 1.27 1.27)
					(thickness 0.15)
				)
				(justify left bottom)
				(hide yes)
			)
		)
		(property "MPN" "GRM155R71H103KA88D"
			(at 90.17 187.96 0)
			(effects
				(font
					(size 1.27 1.27)
					(thickness 0.15)
				)
				(justify left bottom)
				(hide yes)
			)
		)
		(property "Val" "10n"
			(at 73.025 207.645 90)
			(effects
				(font
					(size 1.27 1.27)
					(thickness 0.15)
				)
				(justify right)
			)
		)
		(property "License" "Apache-2.0"
			(at 95.25 187.96 0)
			(effects
				(font
					(size 1.27 1.27)
					(thickness 0.15)
				)
				(justify left bottom)
				(hide yes)
			)
		)
		(property "Author" "Antmicro"
			(at 97.79 187.96 0)
			(effects
				(font
					(size 1.27 1.27)
					(thickness 0.15)
				)
				(justify left bottom)
				(hide yes)
			)
		)
		(property "Voltage" "50V"
			(at 100.33 187.96 0)
			(effects
				(font
					(size 1.27 1.27)
				)
				(justify left bottom)
				(hide yes)
			)
		)
		(property "Dielectric" "X7R"
			(at 102.87 187.96 0)
			(effects
				(font
					(size 1.27 1.27)
				)
				(justify left bottom)
				(hide yes)
			)
		)
		(pin "1"
		)
		(pin "2"
		)
		(instances
			(project "artix-dc-scm"
				(path ""
					(reference "C64")
					(unit 1)
				)
			)
		)
	)
	(symbol
		(lib_id "antmicroCapacitors0402:C_10u_0402")
		(at 369.57 40.64 90)
		(unit 1)
		(exclude_from_sim no)
		(in_bom yes)
		(on_board yes)
		(dnp no)
		(property "Reference" "C83"
			(at 370.205 36.195 90)
			(effects
				(font
					(size 1.27 1.27)
				)
				(justify right)
			)
		)
		(property "Value" "C_10u_0402"
			(at 379.73 20.32 0)
			(effects
				(font
					(size 1.27 1.27)
					(thickness 0.15)
				)
				(justify left bottom)
				(hide yes)
			)
		)
		(property "Footprint" "antmicro-footprints:C_0402_1005Metric"
			(at 382.27 20.32 0)
			(effects
				(font
					(size 1.27 1.27)
					(thickness 0.15)
				)
				(justify left bottom)
				(hide yes)
			)
		)
		(property "Datasheet" "https://www.yageo.com/en/Chart/Download/pdf/CC0402MRX5R5BB106"
			(at 384.81 20.32 0)
			(effects
				(font
					(size 1.27 1.27)
					(thickness 0.15)
				)
				(justify left bottom)
				(hide yes)
			)
		)
		(property "Description" "SMD Multilayer Ceramic Capacitor, 10 µF, 6.3 V, 0402 [1005 Metric], ± 20%, X5R, CC Series"
			(at 369.57 40.64 0)
			(effects
				(font
					(size 1.27 1.27)
				)
				(hide yes)
			)
		)
		(property "Manufacturer" "YAGEO"
			(at 389.89 20.32 0)
			(effects
				(font
					(size 1.27 1.27)
					(thickness 0.15)
				)
				(justify left bottom)
				(hide yes)
			)
		)
		(property "MPN" "CC0402MRX5R5BB106"
			(at 387.35 20.32 0)
			(effects
				(font
					(size 1.27 1.27)
					(thickness 0.15)
				)
				(justify left bottom)
				(hide yes)
			)
		)
		(property "Val" "10u"
			(at 370.205 40.005 90)
			(effects
				(font
					(size 1.27 1.27)
					(thickness 0.15)
				)
				(justify right)
			)
		)
		(property "License" "Apache-2.0"
			(at 392.43 20.32 0)
			(effects
				(font
					(size 1.27 1.27)
					(thickness 0.15)
				)
				(justify left bottom)
				(hide yes)
			)
		)
		(property "Author" "Antmicro"
			(at 394.97 20.32 0)
			(effects
				(font
					(size 1.27 1.27)
					(thickness 0.15)
				)
				(justify left bottom)
				(hide yes)
			)
		)
		(property "Voltage" ""
			(at 397.51 20.32 0)
			(effects
				(font
					(size 1.27 1.27)
				)
				(justify left bottom)
				(hide yes)
			)
		)
		(property "Dielectric" ""
			(at 400.05 20.32 0)
			(effects
				(font
					(size 1.27 1.27)
				)
				(justify left bottom)
				(hide yes)
			)
		)
		(pin "1"
		)
		(pin "2"
		)
		(instances
			(project "artix-dc-scm"
				(path ""
					(reference "C83")
					(unit 1)
				)
			)
		)
	)
	(symbol
		(lib_id "antmicroCapacitors0402:C_10u_0402")
		(at 377.19 40.64 90)
		(unit 1)
		(exclude_from_sim no)
		(in_bom yes)
		(on_board yes)
		(dnp no)
		(property "Reference" "C87"
			(at 377.825 36.195 90)
			(effects
				(font
					(size 1.27 1.27)
				)
				(justify right)
			)
		)
		(property "Value" "C_10u_0402"
			(at 387.35 20.32 0)
			(effects
				(font
					(size 1.27 1.27)
					(thickness 0.15)
				)
				(justify left bottom)
				(hide yes)
			)
		)
		(property "Footprint" "antmicro-footprints:C_0402_1005Metric"
			(at 389.89 20.32 0)
			(effects
				(font
					(size 1.27 1.27)
					(thickness 0.15)
				)
				(justify left bottom)
				(hide yes)
			)
		)
		(property "Datasheet" "https://www.yageo.com/en/Chart/Download/pdf/CC0402MRX5R5BB106"
			(at 392.43 20.32 0)
			(effects
				(font
					(size 1.27 1.27)
					(thickness 0.15)
				)
				(justify left bottom)
				(hide yes)
			)
		)
		(property "Description" "SMD Multilayer Ceramic Capacitor, 10 µF, 6.3 V, 0402 [1005 Metric], ± 20%, X5R, CC Series"
			(at 377.19 40.64 0)
			(effects
				(font
					(size 1.27 1.27)
				)
				(hide yes)
			)
		)
		(property "Manufacturer" "YAGEO"
			(at 397.51 20.32 0)
			(effects
				(font
					(size 1.27 1.27)
					(thickness 0.15)
				)
				(justify left bottom)
				(hide yes)
			)
		)
		(property "MPN" "CC0402MRX5R5BB106"
			(at 394.97 20.32 0)
			(effects
				(font
					(size 1.27 1.27)
					(thickness 0.15)
				)
				(justify left bottom)
				(hide yes)
			)
		)
		(property "Val" "10u"
			(at 377.825 40.005 90)
			(effects
				(font
					(size 1.27 1.27)
					(thickness 0.15)
				)
				(justify right)
			)
		)
		(property "License" "Apache-2.0"
			(at 400.05 20.32 0)
			(effects
				(font
					(size 1.27 1.27)
					(thickness 0.15)
				)
				(justify left bottom)
				(hide yes)
			)
		)
		(property "Author" "Antmicro"
			(at 402.59 20.32 0)
			(effects
				(font
					(size 1.27 1.27)
					(thickness 0.15)
				)
				(justify left bottom)
				(hide yes)
			)
		)
		(property "Voltage" ""
			(at 405.13 20.32 0)
			(effects
				(font
					(size 1.27 1.27)
				)
				(justify left bottom)
				(hide yes)
			)
		)
		(property "Dielectric" ""
			(at 407.67 20.32 0)
			(effects
				(font
					(size 1.27 1.27)
				)
				(justify left bottom)
				(hide yes)
			)
		)
		(pin "1"
		)
		(pin "2"
		)
		(instances
			(project "artix-dc-scm"
				(path ""
					(reference "C87")
					(unit 1)
				)
			)
		)
	)
	(symbol
		(lib_id "antmicropower:GND")
		(at 72.39 208.28 0)
		(unit 1)
		(exclude_from_sim no)
		(in_bom yes)
		(on_board yes)
		(dnp no)
		(property "Reference" "#PWR047"
			(at 72.39 214.63 0)
			(effects
				(font
					(size 1.27 1.27)
				)
				(hide yes)
			)
		)
		(property "Value" "GND"
			(at 72.39 212.09 0)
			(effects
				(font
					(size 1.27 1.27)
				)
			)
		)
		(property "Footprint" ""
			(at 72.39 208.28 0)
			(effects
				(font
					(size 1.27 1.27)
				)
				(hide yes)
			)
		)
		(property "Datasheet" ""
			(at 72.39 208.28 0)
			(effects
				(font
					(size 1.27 1.27)
				)
				(hide yes)
			)
		)
		(property "Description" ""
			(at 72.39 208.28 0)
			(effects
				(font
					(size 1.27 1.27)
				)
				(hide yes)
			)
		)
		(property "Author" "Antmicro"
			(at 81.28 215.9 0)
			(effects
				(font
					(size 1.27 1.27)
					(thickness 0.15)
				)
				(justify left bottom)
				(hide yes)
			)
		)
		(property "License" "Apache-2.0"
			(at 81.28 218.44 0)
			(effects
				(font
					(size 1.27 1.27)
					(thickness 0.15)
				)
				(justify left bottom)
				(hide yes)
			)
		)
		(pin "1"
		)
		(instances
			(project "artix-dc-scm"
				(path ""
					(reference "#PWR047")
					(unit 1)
				)
			)
		)
	)
	(symbol
		(lib_id "antmicroCapacitors0603:C_10u_0603")
		(at 316.23 74.93 90)
		(unit 1)
		(exclude_from_sim no)
		(in_bom yes)
		(on_board yes)
		(dnp no)
		(property "Reference" "C76"
			(at 316.865 70.485 90)
			(effects
				(font
					(size 1.27 1.27)
				)
				(justify right)
			)
		)
		(property "Value" "C_10u_0603"
			(at 326.39 54.61 0)
			(effects
				(font
					(size 1.27 1.27)
					(thickness 0.15)
				)
				(justify left bottom)
				(hide yes)
			)
		)
		(property "Footprint" "antmicro-footprints:C_0603_1608Metric"
			(at 328.93 54.61 0)
			(effects
				(font
					(size 1.27 1.27)
					(thickness 0.15)
				)
				(justify left bottom)
				(hide yes)
			)
		)
		(property "Datasheet" "https://www.murata.com/products/productdetail?partno=GRM188R61A106KE69%23"
			(at 331.47 54.61 0)
			(effects
				(font
					(size 1.27 1.27)
					(thickness 0.15)
				)
				(justify left bottom)
				(hide yes)
			)
		)
		(property "Description" "SMD Multilayer Ceramic Capacitor, 10 µF, 10 V, 0603 [1608 Metric], ± 10%, X5R, GRM Series"
			(at 316.23 74.93 0)
			(effects
				(font
					(size 1.27 1.27)
				)
				(hide yes)
			)
		)
		(property "Manufacturer" "Murata"
			(at 336.55 54.61 0)
			(effects
				(font
					(size 1.27 1.27)
					(thickness 0.15)
				)
				(justify left bottom)
				(hide yes)
			)
		)
		(property "MPN" "GRM188R61A106KE69D"
			(at 334.01 54.61 0)
			(effects
				(font
					(size 1.27 1.27)
					(thickness 0.15)
				)
				(justify left bottom)
				(hide yes)
			)
		)
		(property "Val" "10u"
			(at 316.865 74.295 90)
			(effects
				(font
					(size 1.27 1.27)
					(thickness 0.15)
				)
				(justify right)
			)
		)
		(property "License" "Apache-2.0"
			(at 339.09 54.61 0)
			(effects
				(font
					(size 1.27 1.27)
					(thickness 0.15)
				)
				(justify left bottom)
				(hide yes)
			)
		)
		(property "Author" "Antmicro"
			(at 341.63 54.61 0)
			(effects
				(font
					(size 1.27 1.27)
					(thickness 0.15)
				)
				(justify left bottom)
				(hide yes)
			)
		)
		(property "Voltage" ""
			(at 344.17 54.61 0)
			(effects
				(font
					(size 1.27 1.27)
				)
				(justify left bottom)
				(hide yes)
			)
		)
		(property "Dielectric" "template_dielectric"
			(at 346.71 54.61 0)
			(effects
				(font
					(size 1.27 1.27)
				)
				(justify left bottom)
				(hide yes)
			)
		)
		(pin "1"
		)
		(pin "2"
		)
		(instances
			(project "artix-dc-scm"
				(path ""
					(reference "C76")
					(unit 1)
				)
			)
		)
	)
	(symbol
		(lib_id "antmicroDCDCConverters:TPS62823DLCT")
		(at 323.85 78.74 0)
		(unit 1)
		(exclude_from_sim no)
		(in_bom yes)
		(on_board yes)
		(dnp no)
		(property "Reference" "U11"
			(at 334.01 72.39 0)
			(effects
				(font
					(size 1.27 1.27)
				)
			)
		)
		(property "Value" "TPS62823DLCT"
			(at 334.01 74.93 0)
			(effects
				(font
					(size 1.27 1.27)
				)
			)
		)
		(property "Footprint" "antmicro-footprints:QFN-8_2x1.5mm"
			(at 358.14 82.55 0)
			(effects
				(font
					(size 1.27 1.27)
					(thickness 0.15)
				)
				(justify left bottom)
				(hide yes)
			)
		)
		(property "Datasheet" "https://www.ti.com/lit/ds/symlink/tps62823.pdf?ts=1685970309606&ref_url=https%253A%252F%252Fwww.ti.com%252Fproduct%252FTPS62823%252Fpart-details%252FTPS62823DLCT"
			(at 358.14 85.09 0)
			(effects
				(font
					(size 1.27 1.27)
					(thickness 0.15)
				)
				(justify left bottom)
				(hide yes)
			)
		)
		(property "Description" "DC/DC converter"
			(at 323.85 78.74 0)
			(effects
				(font
					(size 1.27 1.27)
				)
				(hide yes)
			)
		)
		(property "MPN" "TPS62823DLCT"
			(at 358.14 87.63 0)
			(effects
				(font
					(size 1.27 1.27)
					(thickness 0.15)
				)
				(justify left bottom)
				(hide yes)
			)
		)
		(property "Manufacturer" "Texas Instruments"
			(at 358.14 90.17 0)
			(effects
				(font
					(size 1.27 1.27)
					(thickness 0.15)
				)
				(justify left bottom)
				(hide yes)
			)
		)
		(property "Author" "Antmicro"
			(at 358.14 92.71 0)
			(effects
				(font
					(size 1.27 1.27)
					(thickness 0.15)
				)
				(justify left bottom)
				(hide yes)
			)
		)
		(property "License" "Apache-2.0"
			(at 358.14 95.25 0)
			(effects
				(font
					(size 1.27 1.27)
					(thickness 0.15)
				)
				(justify left bottom)
				(hide yes)
			)
		)
		(pin "4"
		)
		(pin "1"
		)
		(pin "2"
		)
		(pin "3"
		)
		(pin "5"
		)
		(pin "6"
		)
		(pin "7"
		)
		(pin "8"
		)
		(instances
			(project "artix-dc-scm"
				(path ""
					(reference "U11")
					(unit 1)
				)
			)
		)
	)
	(symbol
		(lib_id "antmicroCapacitors0402:C_120p_100V_0402")
		(at 353.06 85.09 90)
		(unit 1)
		(exclude_from_sim no)
		(in_bom yes)
		(on_board yes)
		(dnp no)
		(property "Reference" "C80"
			(at 353.695 80.645 90)
			(effects
				(font
					(size 1.27 1.27)
				)
				(justify right)
			)
		)
		(property "Value" "C_120p_0402"
			(at 363.22 64.77 0)
			(effects
				(font
					(size 1.27 1.27)
					(thickness 0.15)
				)
				(justify left bottom)
				(hide yes)
			)
		)
		(property "Footprint" "antmicro-footprints:C_0402_1005Metric"
			(at 365.76 64.77 0)
			(effects
				(font
					(size 1.27 1.27)
					(thickness 0.15)
				)
				(justify left bottom)
				(hide yes)
			)
		)
		(property "Datasheet" "https://www.kemet.com/en/us/capacitors/product/C0402C121J5GACTU.html"
			(at 368.3 64.77 0)
			(effects
				(font
					(size 1.27 1.27)
					(thickness 0.15)
				)
				(justify left bottom)
				(hide yes)
			)
		)
		(property "Description" "120 pF ±2% 100V Ceramic Capacitor C0G, NP0 0402 (1005 Metric)"
			(at 353.06 85.09 0)
			(effects
				(font
					(size 1.27 1.27)
				)
				(hide yes)
			)
		)
		(property "Manufacturer" "KEMET"
			(at 373.38 64.77 0)
			(effects
				(font
					(size 1.27 1.27)
					(thickness 0.15)
				)
				(justify left bottom)
				(hide yes)
			)
		)
		(property "MPN" "C0402C121J5GACTU"
			(at 370.84 64.77 0)
			(effects
				(font
					(size 1.27 1.27)
					(thickness 0.15)
				)
				(justify left bottom)
				(hide yes)
			)
		)
		(property "Val" "120p"
			(at 353.695 84.455 90)
			(effects
				(font
					(size 1.27 1.27)
					(thickness 0.15)
				)
				(justify right)
			)
		)
		(property "License" "Apache-2.0"
			(at 375.92 64.77 0)
			(effects
				(font
					(size 1.27 1.27)
					(thickness 0.15)
				)
				(justify left bottom)
				(hide yes)
			)
		)
		(property "Author" "Antmicro"
			(at 378.46 64.77 0)
			(effects
				(font
					(size 1.27 1.27)
					(thickness 0.15)
				)
				(justify left bottom)
				(hide yes)
			)
		)
		(property "Voltage" "100V"
			(at 381 64.77 0)
			(effects
				(font
					(size 1.27 1.27)
				)
				(justify left bottom)
				(hide yes)
			)
		)
		(property "Dielectric" "C0G"
			(at 383.54 64.77 0)
			(effects
				(font
					(size 1.27 1.27)
				)
				(justify left bottom)
				(hide yes)
			)
		)
		(pin "1"
		)
		(pin "2"
		)
		(instances
			(project "artix-dc-scm"
				(path ""
					(reference "C80")
					(unit 1)
				)
			)
		)
	)
	(symbol
		(lib_id "antmicroResistors0402:R_100k_0402")
		(at 360.68 87.63 270)
		(unit 1)
		(exclude_from_sim no)
		(in_bom yes)
		(on_board yes)
		(dnp no)
		(property "Reference" "R76"
			(at 361.95 88.9 90)
			(effects
				(font
					(size 1.27 1.27)
				)
				(justify left)
			)
		)
		(property "Value" "R_100k_0402"
			(at 347.98 107.95 0)
			(effects
				(font
					(size 1.27 1.27)
					(thickness 0.15)
				)
				(justify left bottom)
				(hide yes)
			)
		)
		(property "Footprint" "antmicro-footprints:R_0402_1005Metric"
			(at 345.44 107.95 0)
			(effects
				(font
					(size 1.27 1.27)
					(thickness 0.15)
				)
				(justify left bottom)
				(hide yes)
			)
		)
		(property "Datasheet" "https://www.bourns.com/docs/product-datasheets/cr.pdf"
			(at 342.9 107.95 0)
			(effects
				(font
					(size 1.27 1.27)
					(thickness 0.15)
				)
				(justify left bottom)
				(hide yes)
			)
		)
		(property "Description" "SMD Chip Resistor, 100 kohm, ± 1%, 62.5 mW, 0402 [1005 Metric], Thick Film, General Purpose"
			(at 360.68 87.63 0)
			(effects
				(font
					(size 1.27 1.27)
				)
				(hide yes)
			)
		)
		(property "Manufacturer" "Bourns"
			(at 337.82 107.95 0)
			(effects
				(font
					(size 1.27 1.27)
					(thickness 0.15)
				)
				(justify left bottom)
				(hide yes)
			)
		)
		(property "MPN" "CR0402-FX-1003GLF"
			(at 340.36 107.95 0)
			(effects
				(font
					(size 1.27 1.27)
					(thickness 0.15)
				)
				(justify left bottom)
				(hide yes)
			)
		)
		(property "Val" "100k"
			(at 361.95 91.44 90)
			(effects
				(font
					(size 1.27 1.27)
					(thickness 0.15)
				)
				(justify left)
			)
		)
		(property "License" "Apache-2.0"
			(at 335.28 107.95 0)
			(effects
				(font
					(size 1.27 1.27)
					(thickness 0.15)
				)
				(justify left bottom)
				(hide yes)
			)
		)
		(property "Author" "Antmicro"
			(at 332.74 107.95 0)
			(effects
				(font
					(size 1.27 1.27)
					(thickness 0.15)
				)
				(justify left bottom)
				(hide yes)
			)
		)
		(property "Tolerance" "1%"
			(at 350.52 107.95 0)
			(effects
				(font
					(size 1.27 1.27)
				)
				(justify left bottom)
				(hide yes)
			)
		)
		(pin "1"
		)
		(pin "2"
		)
		(instances
			(project "artix-dc-scm"
				(path ""
					(reference "R76")
					(unit 1)
				)
			)
		)
	)
	(symbol
		(lib_id "antmicroCapacitors0402:C_10u_0402")
		(at 369.57 85.09 90)
		(unit 1)
		(exclude_from_sim no)
		(in_bom yes)
		(on_board yes)
		(dnp no)
		(property "Reference" "C84"
			(at 370.205 80.645 90)
			(effects
				(font
					(size 1.27 1.27)
				)
				(justify right)
			)
		)
		(property "Value" "C_10u_0402"
			(at 379.73 64.77 0)
			(effects
				(font
					(size 1.27 1.27)
					(thickness 0.15)
				)
				(justify left bottom)
				(hide yes)
			)
		)
		(property "Footprint" "antmicro-footprints:C_0402_1005Metric"
			(at 382.27 64.77 0)
			(effects
				(font
					(size 1.27 1.27)
					(thickness 0.15)
				)
				(justify left bottom)
				(hide yes)
			)
		)
		(property "Datasheet" "https://www.yageo.com/en/Chart/Download/pdf/CC0402MRX5R5BB106"
			(at 384.81 64.77 0)
			(effects
				(font
					(size 1.27 1.27)
					(thickness 0.15)
				)
				(justify left bottom)
				(hide yes)
			)
		)
		(property "Description" "SMD Multilayer Ceramic Capacitor, 10 µF, 6.3 V, 0402 [1005 Metric], ± 20%, X5R, CC Series"
			(at 369.57 85.09 0)
			(effects
				(font
					(size 1.27 1.27)
				)
				(hide yes)
			)
		)
		(property "Manufacturer" "YAGEO"
			(at 389.89 64.77 0)
			(effects
				(font
					(size 1.27 1.27)
					(thickness 0.15)
				)
				(justify left bottom)
				(hide yes)
			)
		)
		(property "MPN" "CC0402MRX5R5BB106"
			(at 387.35 64.77 0)
			(effects
				(font
					(size 1.27 1.27)
					(thickness 0.15)
				)
				(justify left bottom)
				(hide yes)
			)
		)
		(property "Val" "10u"
			(at 370.205 84.455 90)
			(effects
				(font
					(size 1.27 1.27)
					(thickness 0.15)
				)
				(justify right)
			)
		)
		(property "License" "Apache-2.0"
			(at 392.43 64.77 0)
			(effects
				(font
					(size 1.27 1.27)
					(thickness 0.15)
				)
				(justify left bottom)
				(hide yes)
			)
		)
		(property "Author" "Antmicro"
			(at 394.97 64.77 0)
			(effects
				(font
					(size 1.27 1.27)
					(thickness 0.15)
				)
				(justify left bottom)
				(hide yes)
			)
		)
		(property "Voltage" ""
			(at 397.51 64.77 0)
			(effects
				(font
					(size 1.27 1.27)
				)
				(justify left bottom)
				(hide yes)
			)
		)
		(property "Dielectric" ""
			(at 400.05 64.77 0)
			(effects
				(font
					(size 1.27 1.27)
				)
				(justify left bottom)
				(hide yes)
			)
		)
		(pin "1"
		)
		(pin "2"
		)
		(instances
			(project "artix-dc-scm"
				(path ""
					(reference "C84")
					(unit 1)
				)
			)
		)
	)
	(symbol
		(lib_id "antmicroCapacitors0402:C_10u_0402")
		(at 377.19 85.09 90)
		(unit 1)
		(exclude_from_sim no)
		(in_bom yes)
		(on_board yes)
		(dnp no)
		(property "Reference" "C88"
			(at 377.825 80.645 90)
			(effects
				(font
					(size 1.27 1.27)
				)
				(justify right)
			)
		)
		(property "Value" "C_10u_0402"
			(at 387.35 64.77 0)
			(effects
				(font
					(size 1.27 1.27)
					(thickness 0.15)
				)
				(justify left bottom)
				(hide yes)
			)
		)
		(property "Footprint" "antmicro-footprints:C_0402_1005Metric"
			(at 389.89 64.77 0)
			(effects
				(font
					(size 1.27 1.27)
					(thickness 0.15)
				)
				(justify left bottom)
				(hide yes)
			)
		)
		(property "Datasheet" "https://www.yageo.com/en/Chart/Download/pdf/CC0402MRX5R5BB106"
			(at 392.43 64.77 0)
			(effects
				(font
					(size 1.27 1.27)
					(thickness 0.15)
				)
				(justify left bottom)
				(hide yes)
			)
		)
		(property "Description" "SMD Multilayer Ceramic Capacitor, 10 µF, 6.3 V, 0402 [1005 Metric], ± 20%, X5R, CC Series"
			(at 377.19 85.09 0)
			(effects
				(font
					(size 1.27 1.27)
				)
				(hide yes)
			)
		)
		(property "Manufacturer" "YAGEO"
			(at 397.51 64.77 0)
			(effects
				(font
					(size 1.27 1.27)
					(thickness 0.15)
				)
				(justify left bottom)
				(hide yes)
			)
		)
		(property "MPN" "CC0402MRX5R5BB106"
			(at 394.97 64.77 0)
			(effects
				(font
					(size 1.27 1.27)
					(thickness 0.15)
				)
				(justify left bottom)
				(hide yes)
			)
		)
		(property "Val" "10u"
			(at 377.825 84.455 90)
			(effects
				(font
					(size 1.27 1.27)
					(thickness 0.15)
				)
				(justify right)
			)
		)
		(property "License" "Apache-2.0"
			(at 400.05 64.77 0)
			(effects
				(font
					(size 1.27 1.27)
					(thickness 0.15)
				)
				(justify left bottom)
				(hide yes)
			)
		)
		(property "Author" "Antmicro"
			(at 402.59 64.77 0)
			(effects
				(font
					(size 1.27 1.27)
					(thickness 0.15)
				)
				(justify left bottom)
				(hide yes)
			)
		)
		(property "Voltage" ""
			(at 405.13 64.77 0)
			(effects
				(font
					(size 1.27 1.27)
				)
				(justify left bottom)
				(hide yes)
			)
		)
		(property "Dielectric" ""
			(at 407.67 64.77 0)
			(effects
				(font
					(size 1.27 1.27)
				)
				(justify left bottom)
				(hide yes)
			)
		)
		(pin "1"
		)
		(pin "2"
		)
		(instances
			(project "artix-dc-scm"
				(path ""
					(reference "C88")
					(unit 1)
				)
			)
		)
	)
	(symbol
		(lib_id "antmicroCapacitors0603:C_10u_0603")
		(at 316.23 119.38 90)
		(unit 1)
		(exclude_from_sim no)
		(in_bom yes)
		(on_board yes)
		(dnp no)
		(property "Reference" "C78"
			(at 316.865 114.935 90)
			(effects
				(font
					(size 1.27 1.27)
				)
				(justify right)
			)
		)
		(property "Value" "C_10u_0603"
			(at 326.39 99.06 0)
			(effects
				(font
					(size 1.27 1.27)
					(thickness 0.15)
				)
				(justify left bottom)
				(hide yes)
			)
		)
		(property "Footprint" "antmicro-footprints:C_0603_1608Metric"
			(at 328.93 99.06 0)
			(effects
				(font
					(size 1.27 1.27)
					(thickness 0.15)
				)
				(justify left bottom)
				(hide yes)
			)
		)
		(property "Datasheet" "https://www.murata.com/products/productdetail?partno=GRM188R61A106KE69%23"
			(at 331.47 99.06 0)
			(effects
				(font
					(size 1.27 1.27)
					(thickness 0.15)
				)
				(justify left bottom)
				(hide yes)
			)
		)
		(property "Description" "SMD Multilayer Ceramic Capacitor, 10 µF, 10 V, 0603 [1608 Metric], ± 10%, X5R, GRM Series"
			(at 316.23 119.38 0)
			(effects
				(font
					(size 1.27 1.27)
				)
				(hide yes)
			)
		)
		(property "Manufacturer" "Murata"
			(at 336.55 99.06 0)
			(effects
				(font
					(size 1.27 1.27)
					(thickness 0.15)
				)
				(justify left bottom)
				(hide yes)
			)
		)
		(property "MPN" "GRM188R61A106KE69D"
			(at 334.01 99.06 0)
			(effects
				(font
					(size 1.27 1.27)
					(thickness 0.15)
				)
				(justify left bottom)
				(hide yes)
			)
		)
		(property "Val" "10u"
			(at 316.865 118.745 90)
			(effects
				(font
					(size 1.27 1.27)
					(thickness 0.15)
				)
				(justify right)
			)
		)
		(property "License" "Apache-2.0"
			(at 339.09 99.06 0)
			(effects
				(font
					(size 1.27 1.27)
					(thickness 0.15)
				)
				(justify left bottom)
				(hide yes)
			)
		)
		(property "Author" "Antmicro"
			(at 341.63 99.06 0)
			(effects
				(font
					(size 1.27 1.27)
					(thickness 0.15)
				)
				(justify left bottom)
				(hide yes)
			)
		)
		(property "Voltage" ""
			(at 344.17 99.06 0)
			(effects
				(font
					(size 1.27 1.27)
				)
				(justify left bottom)
				(hide yes)
			)
		)
		(property "Dielectric" "template_dielectric"
			(at 346.71 99.06 0)
			(effects
				(font
					(size 1.27 1.27)
				)
				(justify left bottom)
				(hide yes)
			)
		)
		(pin "1"
		)
		(pin "2"
		)
		(instances
			(project "artix-dc-scm"
				(path ""
					(reference "C78")
					(unit 1)
				)
			)
		)
	)
	(symbol
		(lib_id "antmicroDCDCConverters:TPS62823DLCT")
		(at 323.85 123.19 0)
		(unit 1)
		(exclude_from_sim no)
		(in_bom yes)
		(on_board yes)
		(dnp no)
		(property "Reference" "U13"
			(at 334.01 116.84 0)
			(effects
				(font
					(size 1.27 1.27)
				)
			)
		)
		(property "Value" "TPS62823DLCT"
			(at 334.01 119.38 0)
			(effects
				(font
					(size 1.27 1.27)
				)
			)
		)
		(property "Footprint" "antmicro-footprints:QFN-8_2x1.5mm"
			(at 358.14 127 0)
			(effects
				(font
					(size 1.27 1.27)
					(thickness 0.15)
				)
				(justify left bottom)
				(hide yes)
			)
		)
		(property "Datasheet" "https://www.ti.com/lit/ds/symlink/tps62823.pdf?ts=1685970309606&ref_url=https%253A%252F%252Fwww.ti.com%252Fproduct%252FTPS62823%252Fpart-details%252FTPS62823DLCT"
			(at 358.14 129.54 0)
			(effects
				(font
					(size 1.27 1.27)
					(thickness 0.15)
				)
				(justify left bottom)
				(hide yes)
			)
		)
		(property "Description" "DC/DC converter"
			(at 323.85 123.19 0)
			(effects
				(font
					(size 1.27 1.27)
				)
				(hide yes)
			)
		)
		(property "MPN" "TPS62823DLCT"
			(at 358.14 132.08 0)
			(effects
				(font
					(size 1.27 1.27)
					(thickness 0.15)
				)
				(justify left bottom)
				(hide yes)
			)
		)
		(property "Manufacturer" "Texas Instruments"
			(at 358.14 134.62 0)
			(effects
				(font
					(size 1.27 1.27)
					(thickness 0.15)
				)
				(justify left bottom)
				(hide yes)
			)
		)
		(property "Author" "Antmicro"
			(at 358.14 137.16 0)
			(effects
				(font
					(size 1.27 1.27)
					(thickness 0.15)
				)
				(justify left bottom)
				(hide yes)
			)
		)
		(property "License" "Apache-2.0"
			(at 358.14 139.7 0)
			(effects
				(font
					(size 1.27 1.27)
					(thickness 0.15)
				)
				(justify left bottom)
				(hide yes)
			)
		)
		(pin "4"
		)
		(pin "1"
		)
		(pin "2"
		)
		(pin "3"
		)
		(pin "5"
		)
		(pin "6"
		)
		(pin "7"
		)
		(pin "8"
		)
		(instances
			(project "artix-dc-scm"
				(path ""
					(reference "U13")
					(unit 1)
				)
			)
		)
	)
	(symbol
		(lib_id "antmicroCapacitors0402:C_120p_100V_0402")
		(at 353.06 129.54 90)
		(unit 1)
		(exclude_from_sim no)
		(in_bom yes)
		(on_board yes)
		(dnp no)
		(property "Reference" "C82"
			(at 353.695 125.095 90)
			(effects
				(font
					(size 1.27 1.27)
				)
				(justify right)
			)
		)
		(property "Value" "C_120p_0402"
			(at 363.22 109.22 0)
			(effects
				(font
					(size 1.27 1.27)
					(thickness 0.15)
				)
				(justify left bottom)
				(hide yes)
			)
		)
		(property "Footprint" "antmicro-footprints:C_0402_1005Metric"
			(at 365.76 109.22 0)
			(effects
				(font
					(size 1.27 1.27)
					(thickness 0.15)
				)
				(justify left bottom)
				(hide yes)
			)
		)
		(property "Datasheet" "https://www.kemet.com/en/us/capacitors/product/C0402C121J5GACTU.html"
			(at 368.3 109.22 0)
			(effects
				(font
					(size 1.27 1.27)
					(thickness 0.15)
				)
				(justify left bottom)
				(hide yes)
			)
		)
		(property "Description" "120 pF ±2% 100V Ceramic Capacitor C0G, NP0 0402 (1005 Metric)"
			(at 353.06 129.54 0)
			(effects
				(font
					(size 1.27 1.27)
				)
				(hide yes)
			)
		)
		(property "Manufacturer" "KEMET"
			(at 373.38 109.22 0)
			(effects
				(font
					(size 1.27 1.27)
					(thickness 0.15)
				)
				(justify left bottom)
				(hide yes)
			)
		)
		(property "MPN" "C0402C121J5GACTU"
			(at 370.84 109.22 0)
			(effects
				(font
					(size 1.27 1.27)
					(thickness 0.15)
				)
				(justify left bottom)
				(hide yes)
			)
		)
		(property "Val" "120p"
			(at 353.695 128.905 90)
			(effects
				(font
					(size 1.27 1.27)
					(thickness 0.15)
				)
				(justify right)
			)
		)
		(property "License" "Apache-2.0"
			(at 375.92 109.22 0)
			(effects
				(font
					(size 1.27 1.27)
					(thickness 0.15)
				)
				(justify left bottom)
				(hide yes)
			)
		)
		(property "Author" "Antmicro"
			(at 378.46 109.22 0)
			(effects
				(font
					(size 1.27 1.27)
					(thickness 0.15)
				)
				(justify left bottom)
				(hide yes)
			)
		)
		(property "Voltage" "100V"
			(at 381 109.22 0)
			(effects
				(font
					(size 1.27 1.27)
				)
				(justify left bottom)
				(hide yes)
			)
		)
		(property "Dielectric" "C0G"
			(at 383.54 109.22 0)
			(effects
				(font
					(size 1.27 1.27)
				)
				(justify left bottom)
				(hide yes)
			)
		)
		(pin "1"
		)
		(pin "2"
		)
		(instances
			(project "artix-dc-scm"
				(path ""
					(reference "C82")
					(unit 1)
				)
			)
		)
	)
	(symbol
		(lib_id "antmicroResistors0402:R_100k_0402")
		(at 360.68 132.08 270)
		(unit 1)
		(exclude_from_sim no)
		(in_bom yes)
		(on_board yes)
		(dnp no)
		(property "Reference" "R80"
			(at 361.95 133.35 90)
			(effects
				(font
					(size 1.27 1.27)
				)
				(justify left)
			)
		)
		(property "Value" "R_100k_0402"
			(at 347.98 152.4 0)
			(effects
				(font
					(size 1.27 1.27)
					(thickness 0.15)
				)
				(justify left bottom)
				(hide yes)
			)
		)
		(property "Footprint" "antmicro-footprints:R_0402_1005Metric"
			(at 345.44 152.4 0)
			(effects
				(font
					(size 1.27 1.27)
					(thickness 0.15)
				)
				(justify left bottom)
				(hide yes)
			)
		)
		(property "Datasheet" "https://www.bourns.com/docs/product-datasheets/cr.pdf"
			(at 342.9 152.4 0)
			(effects
				(font
					(size 1.27 1.27)
					(thickness 0.15)
				)
				(justify left bottom)
				(hide yes)
			)
		)
		(property "Description" "SMD Chip Resistor, 100 kohm, ± 1%, 62.5 mW, 0402 [1005 Metric], Thick Film, General Purpose"
			(at 360.68 132.08 0)
			(effects
				(font
					(size 1.27 1.27)
				)
				(hide yes)
			)
		)
		(property "Manufacturer" "Bourns"
			(at 337.82 152.4 0)
			(effects
				(font
					(size 1.27 1.27)
					(thickness 0.15)
				)
				(justify left bottom)
				(hide yes)
			)
		)
		(property "MPN" "CR0402-FX-1003GLF"
			(at 340.36 152.4 0)
			(effects
				(font
					(size 1.27 1.27)
					(thickness 0.15)
				)
				(justify left bottom)
				(hide yes)
			)
		)
		(property "Val" "100k"
			(at 361.95 135.89 90)
			(effects
				(font
					(size 1.27 1.27)
					(thickness 0.15)
				)
				(justify left)
			)
		)
		(property "License" "Apache-2.0"
			(at 335.28 152.4 0)
			(effects
				(font
					(size 1.27 1.27)
					(thickness 0.15)
				)
				(justify left bottom)
				(hide yes)
			)
		)
		(property "Author" "Antmicro"
			(at 332.74 152.4 0)
			(effects
				(font
					(size 1.27 1.27)
					(thickness 0.15)
				)
				(justify left bottom)
				(hide yes)
			)
		)
		(property "Tolerance" "1%"
			(at 350.52 152.4 0)
			(effects
				(font
					(size 1.27 1.27)
				)
				(justify left bottom)
				(hide yes)
			)
		)
		(pin "1"
		)
		(pin "2"
		)
		(instances
			(project "artix-dc-scm"
				(path ""
					(reference "R80")
					(unit 1)
				)
			)
		)
	)
	(symbol
		(lib_id "antmicroCapacitors0402:C_10u_0402")
		(at 369.57 129.54 90)
		(unit 1)
		(exclude_from_sim no)
		(in_bom yes)
		(on_board yes)
		(dnp no)
		(property "Reference" "C86"
			(at 370.205 125.095 90)
			(effects
				(font
					(size 1.27 1.27)
				)
				(justify right)
			)
		)
		(property "Value" "C_10u_0402"
			(at 379.73 109.22 0)
			(effects
				(font
					(size 1.27 1.27)
					(thickness 0.15)
				)
				(justify left bottom)
				(hide yes)
			)
		)
		(property "Footprint" "antmicro-footprints:C_0402_1005Metric"
			(at 382.27 109.22 0)
			(effects
				(font
					(size 1.27 1.27)
					(thickness 0.15)
				)
				(justify left bottom)
				(hide yes)
			)
		)
		(property "Datasheet" "https://www.yageo.com/en/Chart/Download/pdf/CC0402MRX5R5BB106"
			(at 384.81 109.22 0)
			(effects
				(font
					(size 1.27 1.27)
					(thickness 0.15)
				)
				(justify left bottom)
				(hide yes)
			)
		)
		(property "Description" "SMD Multilayer Ceramic Capacitor, 10 µF, 6.3 V, 0402 [1005 Metric], ± 20%, X5R, CC Series"
			(at 369.57 129.54 0)
			(effects
				(font
					(size 1.27 1.27)
				)
				(hide yes)
			)
		)
		(property "Manufacturer" "YAGEO"
			(at 389.89 109.22 0)
			(effects
				(font
					(size 1.27 1.27)
					(thickness 0.15)
				)
				(justify left bottom)
				(hide yes)
			)
		)
		(property "MPN" "CC0402MRX5R5BB106"
			(at 387.35 109.22 0)
			(effects
				(font
					(size 1.27 1.27)
					(thickness 0.15)
				)
				(justify left bottom)
				(hide yes)
			)
		)
		(property "Val" "10u"
			(at 370.205 128.905 90)
			(effects
				(font
					(size 1.27 1.27)
					(thickness 0.15)
				)
				(justify right)
			)
		)
		(property "License" "Apache-2.0"
			(at 392.43 109.22 0)
			(effects
				(font
					(size 1.27 1.27)
					(thickness 0.15)
				)
				(justify left bottom)
				(hide yes)
			)
		)
		(property "Author" "Antmicro"
			(at 394.97 109.22 0)
			(effects
				(font
					(size 1.27 1.27)
					(thickness 0.15)
				)
				(justify left bottom)
				(hide yes)
			)
		)
		(property "Voltage" ""
			(at 397.51 109.22 0)
			(effects
				(font
					(size 1.27 1.27)
				)
				(justify left bottom)
				(hide yes)
			)
		)
		(property "Dielectric" ""
			(at 400.05 109.22 0)
			(effects
				(font
					(size 1.27 1.27)
				)
				(justify left bottom)
				(hide yes)
			)
		)
		(pin "1"
		)
		(pin "2"
		)
		(instances
			(project "artix-dc-scm"
				(path ""
					(reference "C86")
					(unit 1)
				)
			)
		)
	)
	(symbol
		(lib_id "antmicroCapacitors0402:C_10u_0402")
		(at 377.19 129.54 90)
		(unit 1)
		(exclude_from_sim no)
		(in_bom yes)
		(on_board yes)
		(dnp no)
		(property "Reference" "C90"
			(at 377.825 125.095 90)
			(effects
				(font
					(size 1.27 1.27)
				)
				(justify right)
			)
		)
		(property "Value" "C_10u_0402"
			(at 387.35 109.22 0)
			(effects
				(font
					(size 1.27 1.27)
					(thickness 0.15)
				)
				(justify left bottom)
				(hide yes)
			)
		)
		(property "Footprint" "antmicro-footprints:C_0402_1005Metric"
			(at 389.89 109.22 0)
			(effects
				(font
					(size 1.27 1.27)
					(thickness 0.15)
				)
				(justify left bottom)
				(hide yes)
			)
		)
		(property "Datasheet" "https://www.yageo.com/en/Chart/Download/pdf/CC0402MRX5R5BB106"
			(at 392.43 109.22 0)
			(effects
				(font
					(size 1.27 1.27)
					(thickness 0.15)
				)
				(justify left bottom)
				(hide yes)
			)
		)
		(property "Description" "SMD Multilayer Ceramic Capacitor, 10 µF, 6.3 V, 0402 [1005 Metric], ± 20%, X5R, CC Series"
			(at 377.19 129.54 0)
			(effects
				(font
					(size 1.27 1.27)
				)
				(hide yes)
			)
		)
		(property "Manufacturer" "YAGEO"
			(at 397.51 109.22 0)
			(effects
				(font
					(size 1.27 1.27)
					(thickness 0.15)
				)
				(justify left bottom)
				(hide yes)
			)
		)
		(property "MPN" "CC0402MRX5R5BB106"
			(at 394.97 109.22 0)
			(effects
				(font
					(size 1.27 1.27)
					(thickness 0.15)
				)
				(justify left bottom)
				(hide yes)
			)
		)
		(property "Val" "10u"
			(at 377.825 128.905 90)
			(effects
				(font
					(size 1.27 1.27)
					(thickness 0.15)
				)
				(justify right)
			)
		)
		(property "License" "Apache-2.0"
			(at 400.05 109.22 0)
			(effects
				(font
					(size 1.27 1.27)
					(thickness 0.15)
				)
				(justify left bottom)
				(hide yes)
			)
		)
		(property "Author" "Antmicro"
			(at 402.59 109.22 0)
			(effects
				(font
					(size 1.27 1.27)
					(thickness 0.15)
				)
				(justify left bottom)
				(hide yes)
			)
		)
		(property "Voltage" ""
			(at 405.13 109.22 0)
			(effects
				(font
					(size 1.27 1.27)
				)
				(justify left bottom)
				(hide yes)
			)
		)
		(property "Dielectric" ""
			(at 407.67 109.22 0)
			(effects
				(font
					(size 1.27 1.27)
				)
				(justify left bottom)
				(hide yes)
			)
		)
		(pin "1"
		)
		(pin "2"
		)
		(instances
			(project "artix-dc-scm"
				(path ""
					(reference "C90")
					(unit 1)
				)
			)
		)
	)
	(symbol
		(lib_id "antmicroResistors0402:R_124k_0402")
		(at 360.68 124.46 270)
		(unit 1)
		(exclude_from_sim no)
		(in_bom yes)
		(on_board yes)
		(dnp no)
		(property "Reference" "R79"
			(at 361.95 125.73 90)
			(effects
				(font
					(size 1.27 1.27)
				)
				(justify left)
			)
		)
		(property "Value" "R_124k_0402"
			(at 347.98 144.78 0)
			(effects
				(font
					(size 1.27 1.27)
					(thickness 0.15)
				)
				(justify left bottom)
				(hide yes)
			)
		)
		(property "Footprint" "antmicro-footprints:R_0402_1005Metric"
			(at 345.44 144.78 0)
			(effects
				(font
					(size 1.27 1.27)
					(thickness 0.15)
				)
				(justify left bottom)
				(hide yes)
			)
		)
		(property "Datasheet" "https://www.bourns.com/docs/product-datasheets/cr.pdf"
			(at 342.9 144.78 0)
			(effects
				(font
					(size 1.27 1.27)
					(thickness 0.15)
				)
				(justify left bottom)
				(hide yes)
			)
		)
		(property "Description" "SMD Chip Resistor, 124 kohm, ± 1%, 100 mW, 0402 [1005 Metric], Thick Film, Precision"
			(at 360.68 124.46 0)
			(effects
				(font
					(size 1.27 1.27)
				)
				(hide yes)
			)
		)
		(property "Manufacturer" "Bourns"
			(at 337.82 144.78 0)
			(effects
				(font
					(size 1.27 1.27)
					(thickness 0.15)
				)
				(justify left bottom)
				(hide yes)
			)
		)
		(property "MPN" "CR0402-FX-1243GLF"
			(at 340.36 144.78 0)
			(effects
				(font
					(size 1.27 1.27)
					(thickness 0.15)
				)
				(justify left bottom)
				(hide yes)
			)
		)
		(property "Val" "124k"
			(at 361.95 128.27 90)
			(effects
				(font
					(size 1.27 1.27)
					(thickness 0.15)
				)
				(justify left)
			)
		)
		(property "License" "Apache-2.0"
			(at 335.28 144.78 0)
			(effects
				(font
					(size 1.27 1.27)
					(thickness 0.15)
				)
				(justify left bottom)
				(hide yes)
			)
		)
		(property "Author" "Antmicro"
			(at 332.74 144.78 0)
			(effects
				(font
					(size 1.27 1.27)
					(thickness 0.15)
				)
				(justify left bottom)
				(hide yes)
			)
		)
		(property "Tolerance" "1%"
			(at 350.52 144.78 0)
			(effects
				(font
					(size 1.27 1.27)
				)
				(justify left bottom)
				(hide yes)
			)
		)
		(pin "1"
		)
		(pin "2"
		)
		(instances
			(project "artix-dc-scm"
				(path ""
					(reference "R79")
					(unit 1)
				)
			)
		)
	)
	(symbol
		(lib_id "antmicroCapacitors0603:C_10u_0603")
		(at 316.23 163.83 90)
		(unit 1)
		(exclude_from_sim no)
		(in_bom yes)
		(on_board yes)
		(dnp no)
		(property "Reference" "C77"
			(at 316.865 159.385 90)
			(effects
				(font
					(size 1.27 1.27)
				)
				(justify right)
			)
		)
		(property "Value" "C_10u_0603"
			(at 326.39 143.51 0)
			(effects
				(font
					(size 1.27 1.27)
					(thickness 0.15)
				)
				(justify left bottom)
				(hide yes)
			)
		)
		(property "Footprint" "antmicro-footprints:C_0603_1608Metric"
			(at 328.93 143.51 0)
			(effects
				(font
					(size 1.27 1.27)
					(thickness 0.15)
				)
				(justify left bottom)
				(hide yes)
			)
		)
		(property "Datasheet" "https://www.murata.com/products/productdetail?partno=GRM188R61A106KE69%23"
			(at 331.47 143.51 0)
			(effects
				(font
					(size 1.27 1.27)
					(thickness 0.15)
				)
				(justify left bottom)
				(hide yes)
			)
		)
		(property "Description" "SMD Multilayer Ceramic Capacitor, 10 µF, 10 V, 0603 [1608 Metric], ± 10%, X5R, GRM Series"
			(at 316.23 163.83 0)
			(effects
				(font
					(size 1.27 1.27)
				)
				(hide yes)
			)
		)
		(property "Manufacturer" "Murata"
			(at 336.55 143.51 0)
			(effects
				(font
					(size 1.27 1.27)
					(thickness 0.15)
				)
				(justify left bottom)
				(hide yes)
			)
		)
		(property "MPN" "GRM188R61A106KE69D"
			(at 334.01 143.51 0)
			(effects
				(font
					(size 1.27 1.27)
					(thickness 0.15)
				)
				(justify left bottom)
				(hide yes)
			)
		)
		(property "Val" "10u"
			(at 316.865 163.195 90)
			(effects
				(font
					(size 1.27 1.27)
					(thickness 0.15)
				)
				(justify right)
			)
		)
		(property "License" "Apache-2.0"
			(at 339.09 143.51 0)
			(effects
				(font
					(size 1.27 1.27)
					(thickness 0.15)
				)
				(justify left bottom)
				(hide yes)
			)
		)
		(property "Author" "Antmicro"
			(at 341.63 143.51 0)
			(effects
				(font
					(size 1.27 1.27)
					(thickness 0.15)
				)
				(justify left bottom)
				(hide yes)
			)
		)
		(property "Voltage" ""
			(at 344.17 143.51 0)
			(effects
				(font
					(size 1.27 1.27)
				)
				(justify left bottom)
				(hide yes)
			)
		)
		(property "Dielectric" "template_dielectric"
			(at 346.71 143.51 0)
			(effects
				(font
					(size 1.27 1.27)
				)
				(justify left bottom)
				(hide yes)
			)
		)
		(pin "1"
		)
		(pin "2"
		)
		(instances
			(project "artix-dc-scm"
				(path ""
					(reference "C77")
					(unit 1)
				)
			)
		)
	)
	(symbol
		(lib_id "antmicroDCDCConverters:TPS62823DLCT")
		(at 323.85 167.64 0)
		(unit 1)
		(exclude_from_sim no)
		(in_bom yes)
		(on_board yes)
		(dnp no)
		(property "Reference" "U12"
			(at 334.01 161.29 0)
			(effects
				(font
					(size 1.27 1.27)
				)
			)
		)
		(property "Value" "TPS62823DLCT"
			(at 334.01 163.83 0)
			(effects
				(font
					(size 1.27 1.27)
				)
			)
		)
		(property "Footprint" "antmicro-footprints:QFN-8_2x1.5mm"
			(at 358.14 171.45 0)
			(effects
				(font
					(size 1.27 1.27)
					(thickness 0.15)
				)
				(justify left bottom)
				(hide yes)
			)
		)
		(property "Datasheet" "https://www.ti.com/lit/ds/symlink/tps62823.pdf?ts=1685970309606&ref_url=https%253A%252F%252Fwww.ti.com%252Fproduct%252FTPS62823%252Fpart-details%252FTPS62823DLCT"
			(at 358.14 173.99 0)
			(effects
				(font
					(size 1.27 1.27)
					(thickness 0.15)
				)
				(justify left bottom)
				(hide yes)
			)
		)
		(property "Description" "DC/DC converter"
			(at 323.85 167.64 0)
			(effects
				(font
					(size 1.27 1.27)
				)
				(hide yes)
			)
		)
		(property "MPN" "TPS62823DLCT"
			(at 358.14 176.53 0)
			(effects
				(font
					(size 1.27 1.27)
					(thickness 0.15)
				)
				(justify left bottom)
				(hide yes)
			)
		)
		(property "Manufacturer" "Texas Instruments"
			(at 358.14 179.07 0)
			(effects
				(font
					(size 1.27 1.27)
					(thickness 0.15)
				)
				(justify left bottom)
				(hide yes)
			)
		)
		(property "Author" "Antmicro"
			(at 358.14 181.61 0)
			(effects
				(font
					(size 1.27 1.27)
					(thickness 0.15)
				)
				(justify left bottom)
				(hide yes)
			)
		)
		(property "License" "Apache-2.0"
			(at 358.14 184.15 0)
			(effects
				(font
					(size 1.27 1.27)
					(thickness 0.15)
				)
				(justify left bottom)
				(hide yes)
			)
		)
		(pin "4"
		)
		(pin "1"
		)
		(pin "2"
		)
		(pin "3"
		)
		(pin "5"
		)
		(pin "6"
		)
		(pin "7"
		)
		(pin "8"
		)
		(instances
			(project "artix-dc-scm"
				(path ""
					(reference "U12")
					(unit 1)
				)
			)
		)
	)
	(symbol
		(lib_id "antmicroCapacitors0402:C_120p_100V_0402")
		(at 353.06 173.99 90)
		(unit 1)
		(exclude_from_sim no)
		(in_bom yes)
		(on_board yes)
		(dnp no)
		(property "Reference" "C81"
			(at 353.695 169.545 90)
			(effects
				(font
					(size 1.27 1.27)
				)
				(justify right)
			)
		)
		(property "Value" "C_120p_0402"
			(at 363.22 153.67 0)
			(effects
				(font
					(size 1.27 1.27)
					(thickness 0.15)
				)
				(justify left bottom)
				(hide yes)
			)
		)
		(property "Footprint" "antmicro-footprints:C_0402_1005Metric"
			(at 365.76 153.67 0)
			(effects
				(font
					(size 1.27 1.27)
					(thickness 0.15)
				)
				(justify left bottom)
				(hide yes)
			)
		)
		(property "Datasheet" "https://www.kemet.com/en/us/capacitors/product/C0402C121J5GACTU.html"
			(at 368.3 153.67 0)
			(effects
				(font
					(size 1.27 1.27)
					(thickness 0.15)
				)
				(justify left bottom)
				(hide yes)
			)
		)
		(property "Description" "120 pF ±2% 100V Ceramic Capacitor C0G, NP0 0402 (1005 Metric)"
			(at 353.06 173.99 0)
			(effects
				(font
					(size 1.27 1.27)
				)
				(hide yes)
			)
		)
		(property "Manufacturer" "KEMET"
			(at 373.38 153.67 0)
			(effects
				(font
					(size 1.27 1.27)
					(thickness 0.15)
				)
				(justify left bottom)
				(hide yes)
			)
		)
		(property "MPN" "C0402C121J5GACTU"
			(at 370.84 153.67 0)
			(effects
				(font
					(size 1.27 1.27)
					(thickness 0.15)
				)
				(justify left bottom)
				(hide yes)
			)
		)
		(property "Val" "120p"
			(at 353.695 173.355 90)
			(effects
				(font
					(size 1.27 1.27)
					(thickness 0.15)
				)
				(justify right)
			)
		)
		(property "License" "Apache-2.0"
			(at 375.92 153.67 0)
			(effects
				(font
					(size 1.27 1.27)
					(thickness 0.15)
				)
				(justify left bottom)
				(hide yes)
			)
		)
		(property "Author" "Antmicro"
			(at 378.46 153.67 0)
			(effects
				(font
					(size 1.27 1.27)
					(thickness 0.15)
				)
				(justify left bottom)
				(hide yes)
			)
		)
		(property "Voltage" "100V"
			(at 381 153.67 0)
			(effects
				(font
					(size 1.27 1.27)
				)
				(justify left bottom)
				(hide yes)
			)
		)
		(property "Dielectric" "C0G"
			(at 383.54 153.67 0)
			(effects
				(font
					(size 1.27 1.27)
				)
				(justify left bottom)
				(hide yes)
			)
		)
		(pin "1"
		)
		(pin "2"
		)
		(instances
			(project "artix-dc-scm"
				(path ""
					(reference "C81")
					(unit 1)
				)
			)
		)
	)
	(symbol
		(lib_id "antmicroResistors0402:R_100k_0402")
		(at 360.68 176.53 270)
		(unit 1)
		(exclude_from_sim no)
		(in_bom yes)
		(on_board yes)
		(dnp no)
		(property "Reference" "R78"
			(at 361.95 177.8 90)
			(effects
				(font
					(size 1.27 1.27)
				)
				(justify left)
			)
		)
		(property "Value" "R_100k_0402"
			(at 347.98 196.85 0)
			(effects
				(font
					(size 1.27 1.27)
					(thickness 0.15)
				)
				(justify left bottom)
				(hide yes)
			)
		)
		(property "Footprint" "antmicro-footprints:R_0402_1005Metric"
			(at 345.44 196.85 0)
			(effects
				(font
					(size 1.27 1.27)
					(thickness 0.15)
				)
				(justify left bottom)
				(hide yes)
			)
		)
		(property "Datasheet" "https://www.bourns.com/docs/product-datasheets/cr.pdf"
			(at 342.9 196.85 0)
			(effects
				(font
					(size 1.27 1.27)
					(thickness 0.15)
				)
				(justify left bottom)
				(hide yes)
			)
		)
		(property "Description" "SMD Chip Resistor, 100 kohm, ± 1%, 62.5 mW, 0402 [1005 Metric], Thick Film, General Purpose"
			(at 360.68 176.53 0)
			(effects
				(font
					(size 1.27 1.27)
				)
				(hide yes)
			)
		)
		(property "Manufacturer" "Bourns"
			(at 337.82 196.85 0)
			(effects
				(font
					(size 1.27 1.27)
					(thickness 0.15)
				)
				(justify left bottom)
				(hide yes)
			)
		)
		(property "MPN" "CR0402-FX-1003GLF"
			(at 340.36 196.85 0)
			(effects
				(font
					(size 1.27 1.27)
					(thickness 0.15)
				)
				(justify left bottom)
				(hide yes)
			)
		)
		(property "Val" "100k"
			(at 361.95 180.34 90)
			(effects
				(font
					(size 1.27 1.27)
					(thickness 0.15)
				)
				(justify left)
			)
		)
		(property "License" "Apache-2.0"
			(at 335.28 196.85 0)
			(effects
				(font
					(size 1.27 1.27)
					(thickness 0.15)
				)
				(justify left bottom)
				(hide yes)
			)
		)
		(property "Author" "Antmicro"
			(at 332.74 196.85 0)
			(effects
				(font
					(size 1.27 1.27)
					(thickness 0.15)
				)
				(justify left bottom)
				(hide yes)
			)
		)
		(property "Tolerance" "1%"
			(at 350.52 196.85 0)
			(effects
				(font
					(size 1.27 1.27)
				)
				(justify left bottom)
				(hide yes)
			)
		)
		(pin "1"
		)
		(pin "2"
		)
		(instances
			(project "artix-dc-scm"
				(path ""
					(reference "R78")
					(unit 1)
				)
			)
		)
	)
	(symbol
		(lib_id "antmicroCapacitors0402:C_10u_0402")
		(at 369.57 173.99 90)
		(unit 1)
		(exclude_from_sim no)
		(in_bom yes)
		(on_board yes)
		(dnp no)
		(property "Reference" "C85"
			(at 370.205 169.545 90)
			(effects
				(font
					(size 1.27 1.27)
				)
				(justify right)
			)
		)
		(property "Value" "C_10u_0402"
			(at 379.73 153.67 0)
			(effects
				(font
					(size 1.27 1.27)
					(thickness 0.15)
				)
				(justify left bottom)
				(hide yes)
			)
		)
		(property "Footprint" "antmicro-footprints:C_0402_1005Metric"
			(at 382.27 153.67 0)
			(effects
				(font
					(size 1.27 1.27)
					(thickness 0.15)
				)
				(justify left bottom)
				(hide yes)
			)
		)
		(property "Datasheet" "https://www.yageo.com/en/Chart/Download/pdf/CC0402MRX5R5BB106"
			(at 384.81 153.67 0)
			(effects
				(font
					(size 1.27 1.27)
					(thickness 0.15)
				)
				(justify left bottom)
				(hide yes)
			)
		)
		(property "Description" "SMD Multilayer Ceramic Capacitor, 10 µF, 6.3 V, 0402 [1005 Metric], ± 20%, X5R, CC Series"
			(at 369.57 173.99 0)
			(effects
				(font
					(size 1.27 1.27)
				)
				(hide yes)
			)
		)
		(property "Manufacturer" "YAGEO"
			(at 389.89 153.67 0)
			(effects
				(font
					(size 1.27 1.27)
					(thickness 0.15)
				)
				(justify left bottom)
				(hide yes)
			)
		)
		(property "MPN" "CC0402MRX5R5BB106"
			(at 387.35 153.67 0)
			(effects
				(font
					(size 1.27 1.27)
					(thickness 0.15)
				)
				(justify left bottom)
				(hide yes)
			)
		)
		(property "Val" "10u"
			(at 370.205 173.355 90)
			(effects
				(font
					(size 1.27 1.27)
					(thickness 0.15)
				)
				(justify right)
			)
		)
		(property "License" "Apache-2.0"
			(at 392.43 153.67 0)
			(effects
				(font
					(size 1.27 1.27)
					(thickness 0.15)
				)
				(justify left bottom)
				(hide yes)
			)
		)
		(property "Author" "Antmicro"
			(at 394.97 153.67 0)
			(effects
				(font
					(size 1.27 1.27)
					(thickness 0.15)
				)
				(justify left bottom)
				(hide yes)
			)
		)
		(property "Voltage" ""
			(at 397.51 153.67 0)
			(effects
				(font
					(size 1.27 1.27)
				)
				(justify left bottom)
				(hide yes)
			)
		)
		(property "Dielectric" ""
			(at 400.05 153.67 0)
			(effects
				(font
					(size 1.27 1.27)
				)
				(justify left bottom)
				(hide yes)
			)
		)
		(pin "1"
		)
		(pin "2"
		)
		(instances
			(project "artix-dc-scm"
				(path ""
					(reference "C85")
					(unit 1)
				)
			)
		)
	)
	(symbol
		(lib_id "antmicroCapacitors0402:C_10u_0402")
		(at 377.19 173.99 90)
		(unit 1)
		(exclude_from_sim no)
		(in_bom yes)
		(on_board yes)
		(dnp no)
		(property "Reference" "C89"
			(at 377.825 169.545 90)
			(effects
				(font
					(size 1.27 1.27)
				)
				(justify right)
			)
		)
		(property "Value" "C_10u_0402"
			(at 387.35 153.67 0)
			(effects
				(font
					(size 1.27 1.27)
					(thickness 0.15)
				)
				(justify left bottom)
				(hide yes)
			)
		)
		(property "Footprint" "antmicro-footprints:C_0402_1005Metric"
			(at 389.89 153.67 0)
			(effects
				(font
					(size 1.27 1.27)
					(thickness 0.15)
				)
				(justify left bottom)
				(hide yes)
			)
		)
		(property "Datasheet" "https://www.yageo.com/en/Chart/Download/pdf/CC0402MRX5R5BB106"
			(at 392.43 153.67 0)
			(effects
				(font
					(size 1.27 1.27)
					(thickness 0.15)
				)
				(justify left bottom)
				(hide yes)
			)
		)
		(property "Description" "SMD Multilayer Ceramic Capacitor, 10 µF, 6.3 V, 0402 [1005 Metric], ± 20%, X5R, CC Series"
			(at 377.19 173.99 0)
			(effects
				(font
					(size 1.27 1.27)
				)
				(hide yes)
			)
		)
		(property "Manufacturer" "YAGEO"
			(at 397.51 153.67 0)
			(effects
				(font
					(size 1.27 1.27)
					(thickness 0.15)
				)
				(justify left bottom)
				(hide yes)
			)
		)
		(property "MPN" "CC0402MRX5R5BB106"
			(at 394.97 153.67 0)
			(effects
				(font
					(size 1.27 1.27)
					(thickness 0.15)
				)
				(justify left bottom)
				(hide yes)
			)
		)
		(property "Val" "10u"
			(at 377.825 173.355 90)
			(effects
				(font
					(size 1.27 1.27)
					(thickness 0.15)
				)
				(justify right)
			)
		)
		(property "License" "Apache-2.0"
			(at 400.05 153.67 0)
			(effects
				(font
					(size 1.27 1.27)
					(thickness 0.15)
				)
				(justify left bottom)
				(hide yes)
			)
		)
		(property "Author" "Antmicro"
			(at 402.59 153.67 0)
			(effects
				(font
					(size 1.27 1.27)
					(thickness 0.15)
				)
				(justify left bottom)
				(hide yes)
			)
		)
		(property "Voltage" ""
			(at 405.13 153.67 0)
			(effects
				(font
					(size 1.27 1.27)
				)
				(justify left bottom)
				(hide yes)
			)
		)
		(property "Dielectric" ""
			(at 407.67 153.67 0)
			(effects
				(font
					(size 1.27 1.27)
				)
				(justify left bottom)
				(hide yes)
			)
		)
		(pin "1"
		)
		(pin "2"
		)
		(instances
			(project "artix-dc-scm"
				(path ""
					(reference "C89")
					(unit 1)
				)
			)
		)
	)
	(symbol
		(lib_id "antmicropower:PWR_FLAG")
		(at 393.7 78.74 0)
		(unit 1)
		(exclude_from_sim no)
		(in_bom yes)
		(on_board yes)
		(dnp no)
		(property "Reference" "#FLG0122"
			(at 393.7 76.835 0)
			(effects
				(font
					(size 1.27 1.27)
				)
				(hide yes)
			)
		)
		(property "Value" "PWR_FLAG"
			(at 393.7 74.93 0)
			(effects
				(font
					(size 1.27 1.27)
				)
			)
		)
		(property "Footprint" ""
			(at 393.7 78.74 0)
			(effects
				(font
					(size 1.27 1.27)
				)
				(hide yes)
			)
		)
		(property "Datasheet" ""
			(at 393.7 78.74 0)
			(effects
				(font
					(size 1.27 1.27)
				)
				(hide yes)
			)
		)
		(property "Description" ""
			(at 393.7 78.74 0)
			(effects
				(font
					(size 1.27 1.27)
				)
				(hide yes)
			)
		)
		(pin "1"
		)
		(instances
			(project "artix-dc-scm"
				(path ""
					(reference "#FLG0122")
					(unit 1)
				)
			)
		)
	)
	(symbol
		(lib_id "antmicropower:PWR_FLAG")
		(at 393.7 212.09 0)
		(unit 1)
		(exclude_from_sim no)
		(in_bom yes)
		(on_board yes)
		(dnp no)
		(property "Reference" "#FLG0118"
			(at 393.7 210.185 0)
			(effects
				(font
					(size 1.27 1.27)
				)
				(hide yes)
			)
		)
		(property "Value" "PWR_FLAG"
			(at 393.7 208.28 0)
			(effects
				(font
					(size 1.27 1.27)
				)
			)
		)
		(property "Footprint" ""
			(at 393.7 212.09 0)
			(effects
				(font
					(size 1.27 1.27)
				)
				(hide yes)
			)
		)
		(property "Datasheet" ""
			(at 393.7 212.09 0)
			(effects
				(font
					(size 1.27 1.27)
				)
				(hide yes)
			)
		)
		(property "Description" ""
			(at 393.7 212.09 0)
			(effects
				(font
					(size 1.27 1.27)
				)
				(hide yes)
			)
		)
		(pin "1"
		)
		(instances
			(project "artix-dc-scm"
				(path ""
					(reference "#FLG0118")
					(unit 1)
				)
			)
		)
	)
	(symbol
		(lib_id "antmicropower:GND")
		(at 369.57 218.44 0)
		(unit 1)
		(exclude_from_sim no)
		(in_bom yes)
		(on_board yes)
		(dnp no)
		(property "Reference" "#PWR0294"
			(at 369.57 224.79 0)
			(effects
				(font
					(size 1.27 1.27)
				)
				(hide yes)
			)
		)
		(property "Value" "GND"
			(at 369.57 222.25 0)
			(effects
				(font
					(size 1.27 1.27)
				)
			)
		)
		(property "Footprint" ""
			(at 369.57 218.44 0)
			(effects
				(font
					(size 1.27 1.27)
				)
				(hide yes)
			)
		)
		(property "Datasheet" ""
			(at 369.57 218.44 0)
			(effects
				(font
					(size 1.27 1.27)
				)
				(hide yes)
			)
		)
		(property "Description" ""
			(at 369.57 218.44 0)
			(effects
				(font
					(size 1.27 1.27)
				)
				(hide yes)
			)
		)
		(property "Author" "Antmicro"
			(at 378.46 226.06 0)
			(effects
				(font
					(size 1.27 1.27)
					(thickness 0.15)
				)
				(justify left bottom)
				(hide yes)
			)
		)
		(property "License" "Apache-2.0"
			(at 378.46 228.6 0)
			(effects
				(font
					(size 1.27 1.27)
					(thickness 0.15)
				)
				(justify left bottom)
				(hide yes)
			)
		)
		(pin "1"
		)
		(instances
			(project "artix-dc-scm"
				(path ""
					(reference "#PWR0294")
					(unit 1)
				)
			)
		)
	)
	(symbol
		(lib_id "antmicropower:GND")
		(at 377.19 85.09 0)
		(unit 1)
		(exclude_from_sim no)
		(in_bom yes)
		(on_board yes)
		(dnp no)
		(property "Reference" "#PWR0310"
			(at 377.19 91.44 0)
			(effects
				(font
					(size 1.27 1.27)
				)
				(hide yes)
			)
		)
		(property "Value" "GND"
			(at 377.19 88.9 0)
			(effects
				(font
					(size 1.27 1.27)
				)
			)
		)
		(property "Footprint" ""
			(at 377.19 85.09 0)
			(effects
				(font
					(size 1.27 1.27)
				)
				(hide yes)
			)
		)
		(property "Datasheet" ""
			(at 377.19 85.09 0)
			(effects
				(font
					(size 1.27 1.27)
				)
				(hide yes)
			)
		)
		(property "Description" ""
			(at 377.19 85.09 0)
			(effects
				(font
					(size 1.27 1.27)
				)
				(hide yes)
			)
		)
		(property "Author" "Antmicro"
			(at 386.08 92.71 0)
			(effects
				(font
					(size 1.27 1.27)
					(thickness 0.15)
				)
				(justify left bottom)
				(hide yes)
			)
		)
		(property "License" "Apache-2.0"
			(at 386.08 95.25 0)
			(effects
				(font
					(size 1.27 1.27)
					(thickness 0.15)
				)
				(justify left bottom)
				(hide yes)
			)
		)
		(pin "1"
		)
		(instances
			(project "artix-dc-scm"
				(path ""
					(reference "#PWR0310")
					(unit 1)
				)
			)
		)
	)
	(symbol
		(lib_id "antmicropower:GND")
		(at 316.23 163.83 0)
		(unit 1)
		(exclude_from_sim no)
		(in_bom yes)
		(on_board yes)
		(dnp no)
		(property "Reference" "#PWR0296"
			(at 316.23 170.18 0)
			(effects
				(font
					(size 1.27 1.27)
				)
				(hide yes)
			)
		)
		(property "Value" "GND"
			(at 316.23 167.64 0)
			(effects
				(font
					(size 1.27 1.27)
				)
			)
		)
		(property "Footprint" ""
			(at 316.23 163.83 0)
			(effects
				(font
					(size 1.27 1.27)
				)
				(hide yes)
			)
		)
		(property "Datasheet" ""
			(at 316.23 163.83 0)
			(effects
				(font
					(size 1.27 1.27)
				)
				(hide yes)
			)
		)
		(property "Description" ""
			(at 316.23 163.83 0)
			(effects
				(font
					(size 1.27 1.27)
				)
				(hide yes)
			)
		)
		(property "Author" "Antmicro"
			(at 325.12 171.45 0)
			(effects
				(font
					(size 1.27 1.27)
					(thickness 0.15)
				)
				(justify left bottom)
				(hide yes)
			)
		)
		(property "License" "Apache-2.0"
			(at 325.12 173.99 0)
			(effects
				(font
					(size 1.27 1.27)
					(thickness 0.15)
				)
				(justify left bottom)
				(hide yes)
			)
		)
		(pin "1"
		)
		(instances
			(project "artix-dc-scm"
				(path ""
					(reference "#PWR0296")
					(unit 1)
				)
			)
		)
	)
	(symbol
		(lib_id "antmicropower:GND")
		(at 360.68 181.61 0)
		(unit 1)
		(exclude_from_sim no)
		(in_bom yes)
		(on_board yes)
		(dnp no)
		(property "Reference" "#PWR0288"
			(at 360.68 187.96 0)
			(effects
				(font
					(size 1.27 1.27)
				)
				(hide yes)
			)
		)
		(property "Value" "GND"
			(at 360.68 185.42 0)
			(effects
				(font
					(size 1.27 1.27)
				)
			)
		)
		(property "Footprint" ""
			(at 360.68 181.61 0)
			(effects
				(font
					(size 1.27 1.27)
				)
				(hide yes)
			)
		)
		(property "Datasheet" ""
			(at 360.68 181.61 0)
			(effects
				(font
					(size 1.27 1.27)
				)
				(hide yes)
			)
		)
		(property "Description" ""
			(at 360.68 181.61 0)
			(effects
				(font
					(size 1.27 1.27)
				)
				(hide yes)
			)
		)
		(property "Author" "Antmicro"
			(at 369.57 189.23 0)
			(effects
				(font
					(size 1.27 1.27)
					(thickness 0.15)
				)
				(justify left bottom)
				(hide yes)
			)
		)
		(property "License" "Apache-2.0"
			(at 369.57 191.77 0)
			(effects
				(font
					(size 1.27 1.27)
					(thickness 0.15)
				)
				(justify left bottom)
				(hide yes)
			)
		)
		(pin "1"
		)
		(instances
			(project "artix-dc-scm"
				(path ""
					(reference "#PWR0288")
					(unit 1)
				)
			)
		)
	)
	(symbol
		(lib_id "antmicropower:PWR_FLAG")
		(at 393.7 123.19 0)
		(unit 1)
		(exclude_from_sim no)
		(in_bom yes)
		(on_board yes)
		(dnp no)
		(property "Reference" "#FLG0121"
			(at 393.7 121.285 0)
			(effects
				(font
					(size 1.27 1.27)
				)
				(hide yes)
			)
		)
		(property "Value" "PWR_FLAG"
			(at 393.7 119.38 0)
			(effects
				(font
					(size 1.27 1.27)
				)
			)
		)
		(property "Footprint" ""
			(at 393.7 123.19 0)
			(effects
				(font
					(size 1.27 1.27)
				)
				(hide yes)
			)
		)
		(property "Datasheet" ""
			(at 393.7 123.19 0)
			(effects
				(font
					(size 1.27 1.27)
				)
				(hide yes)
			)
		)
		(property "Description" ""
			(at 393.7 123.19 0)
			(effects
				(font
					(size 1.27 1.27)
				)
				(hide yes)
			)
		)
		(pin "1"
		)
		(instances
			(project "artix-dc-scm"
				(path ""
					(reference "#FLG0121")
					(unit 1)
				)
			)
		)
	)
	(symbol
		(lib_id "antmicropower:GND")
		(at 316.23 30.48 0)
		(unit 1)
		(exclude_from_sim no)
		(in_bom yes)
		(on_board yes)
		(dnp no)
		(property "Reference" "#PWR0307"
			(at 316.23 36.83 0)
			(effects
				(font
					(size 1.27 1.27)
				)
				(hide yes)
			)
		)
		(property "Value" "GND"
			(at 316.23 34.29 0)
			(effects
				(font
					(size 1.27 1.27)
				)
			)
		)
		(property "Footprint" ""
			(at 316.23 30.48 0)
			(effects
				(font
					(size 1.27 1.27)
				)
				(hide yes)
			)
		)
		(property "Datasheet" ""
			(at 316.23 30.48 0)
			(effects
				(font
					(size 1.27 1.27)
				)
				(hide yes)
			)
		)
		(property "Description" ""
			(at 316.23 30.48 0)
			(effects
				(font
					(size 1.27 1.27)
				)
				(hide yes)
			)
		)
		(property "Author" "Antmicro"
			(at 325.12 38.1 0)
			(effects
				(font
					(size 1.27 1.27)
					(thickness 0.15)
				)
				(justify left bottom)
				(hide yes)
			)
		)
		(property "License" "Apache-2.0"
			(at 325.12 40.64 0)
			(effects
				(font
					(size 1.27 1.27)
					(thickness 0.15)
				)
				(justify left bottom)
				(hide yes)
			)
		)
		(pin "1"
		)
		(instances
			(project "artix-dc-scm"
				(path ""
					(reference "#PWR0307")
					(unit 1)
				)
			)
		)
	)
	(symbol
		(lib_id "antmicropower:GND")
		(at 377.19 218.44 0)
		(unit 1)
		(exclude_from_sim no)
		(in_bom yes)
		(on_board yes)
		(dnp no)
		(property "Reference" "#PWR0293"
			(at 377.19 224.79 0)
			(effects
				(font
					(size 1.27 1.27)
				)
				(hide yes)
			)
		)
		(property "Value" "GND"
			(at 377.19 222.25 0)
			(effects
				(font
					(size 1.27 1.27)
				)
			)
		)
		(property "Footprint" ""
			(at 377.19 218.44 0)
			(effects
				(font
					(size 1.27 1.27)
				)
				(hide yes)
			)
		)
		(property "Datasheet" ""
			(at 377.19 218.44 0)
			(effects
				(font
					(size 1.27 1.27)
				)
				(hide yes)
			)
		)
		(property "Description" ""
			(at 377.19 218.44 0)
			(effects
				(font
					(size 1.27 1.27)
				)
				(hide yes)
			)
		)
		(property "Author" "Antmicro"
			(at 386.08 226.06 0)
			(effects
				(font
					(size 1.27 1.27)
					(thickness 0.15)
				)
				(justify left bottom)
				(hide yes)
			)
		)
		(property "License" "Apache-2.0"
			(at 386.08 228.6 0)
			(effects
				(font
					(size 1.27 1.27)
					(thickness 0.15)
				)
				(justify left bottom)
				(hide yes)
			)
		)
		(pin "1"
		)
		(instances
			(project "artix-dc-scm"
				(path ""
					(reference "#PWR0293")
					(unit 1)
				)
			)
		)
	)
	(symbol
		(lib_id "antmicroLEDIndicationDiscrete:LED_G_0603_LG_L29K-G2J1-24-Z")
		(at 247.65 187.96 0)
		(unit 1)
		(exclude_from_sim no)
		(in_bom yes)
		(on_board yes)
		(dnp no)
		(fields_autoplaced yes)
		(property "Reference" "D5"
			(at 250.19 177.8 0)
			(effects
				(font
					(size 1.27 1.27)
				)
			)
		)
		(property "Value" "LED_G_0603_LG_L29K-G2J1-24-Z"
			(at 251.46 183.515 0)
			(effects
				(font
					(size 1.27 1.27)
					(thickness 0.15)
				)
				(hide yes)
			)
		)
		(property "Footprint" "antmicro-footprints:LED_0603_1608Metric_G"
			(at 270.51 198.12 0)
			(effects
				(font
					(size 1.27 1.27)
					(thickness 0.15)
				)
				(justify left bottom)
				(hide yes)
			)
		)
		(property "Datasheet" "https://look.ams-osram.com/m/19ee86b3ae0ee95b/original/LG-L29K.pdf"
			(at 270.51 200.66 0)
			(effects
				(font
					(size 1.27 1.27)
					(thickness 0.15)
				)
				(justify left bottom)
				(hide yes)
			)
		)
		(property "Description" "LED, Green, SMD, 0603, 20 mA, 1.7 V, 570 nm"
			(at 247.65 187.96 0)
			(effects
				(font
					(size 1.27 1.27)
				)
				(hide yes)
			)
		)
		(property "MPN" "LG L29K-G2J1-24-Z"
			(at 250.19 180.34 0)
			(effects
				(font
					(size 1.27 1.27)
					(thickness 0.15)
				)
			)
		)
		(property "Manufacturer" "OSRAM"
			(at 270.51 205.74 0)
			(effects
				(font
					(size 1.27 1.27)
					(thickness 0.15)
				)
				(justify left bottom)
				(hide yes)
			)
		)
		(property "Author" "Antmicro"
			(at 270.51 208.28 0)
			(effects
				(font
					(size 1.27 1.27)
					(thickness 0.15)
				)
				(justify left bottom)
				(hide yes)
			)
		)
		(property "License" "Apache-2.0"
			(at 270.51 210.82 0)
			(effects
				(font
					(size 1.27 1.27)
					(thickness 0.15)
				)
				(justify left bottom)
				(hide yes)
			)
		)
		(property "Color" "Green"
			(at 250.19 182.88 0)
			(effects
				(font
					(size 1.27 1.27)
				)
			)
		)
		(pin "1"
		)
		(pin "2"
		)
		(instances
			(project "artix-dc-scm"
				(path ""
					(reference "D5")
					(unit 1)
				)
			)
		)
	)
	(symbol
		(lib_id "antmicropower:GND")
		(at 345.44 92.71 0)
		(unit 1)
		(exclude_from_sim no)
		(in_bom yes)
		(on_board yes)
		(dnp no)
		(property "Reference" "#PWR0305"
			(at 345.44 99.06 0)
			(effects
				(font
					(size 1.27 1.27)
				)
				(hide yes)
			)
		)
		(property "Value" "GND"
			(at 345.44 96.52 0)
			(effects
				(font
					(size 1.27 1.27)
				)
			)
		)
		(property "Footprint" ""
			(at 345.44 92.71 0)
			(effects
				(font
					(size 1.27 1.27)
				)
				(hide yes)
			)
		)
		(property "Datasheet" ""
			(at 345.44 92.71 0)
			(effects
				(font
					(size 1.27 1.27)
				)
				(hide yes)
			)
		)
		(property "Description" ""
			(at 345.44 92.71 0)
			(effects
				(font
					(size 1.27 1.27)
				)
				(hide yes)
			)
		)
		(property "Author" "Antmicro"
			(at 354.33 100.33 0)
			(effects
				(font
					(size 1.27 1.27)
					(thickness 0.15)
				)
				(justify left bottom)
				(hide yes)
			)
		)
		(property "License" "Apache-2.0"
			(at 354.33 102.87 0)
			(effects
				(font
					(size 1.27 1.27)
					(thickness 0.15)
				)
				(justify left bottom)
				(hide yes)
			)
		)
		(pin "1"
		)
		(instances
			(project "artix-dc-scm"
				(path ""
					(reference "#PWR0305")
					(unit 1)
				)
			)
		)
	)
	(symbol
		(lib_id "antmicropower:GND")
		(at 377.19 173.99 0)
		(unit 1)
		(exclude_from_sim no)
		(in_bom yes)
		(on_board yes)
		(dnp no)
		(property "Reference" "#PWR0290"
			(at 377.19 180.34 0)
			(effects
				(font
					(size 1.27 1.27)
				)
				(hide yes)
			)
		)
		(property "Value" "GND"
			(at 377.19 177.8 0)
			(effects
				(font
					(size 1.27 1.27)
				)
			)
		)
		(property "Footprint" ""
			(at 377.19 173.99 0)
			(effects
				(font
					(size 1.27 1.27)
				)
				(hide yes)
			)
		)
		(property "Datasheet" ""
			(at 377.19 173.99 0)
			(effects
				(font
					(size 1.27 1.27)
				)
				(hide yes)
			)
		)
		(property "Description" ""
			(at 377.19 173.99 0)
			(effects
				(font
					(size 1.27 1.27)
				)
				(hide yes)
			)
		)
		(property "Author" "Antmicro"
			(at 386.08 181.61 0)
			(effects
				(font
					(size 1.27 1.27)
					(thickness 0.15)
				)
				(justify left bottom)
				(hide yes)
			)
		)
		(property "License" "Apache-2.0"
			(at 386.08 184.15 0)
			(effects
				(font
					(size 1.27 1.27)
					(thickness 0.15)
				)
				(justify left bottom)
				(hide yes)
			)
		)
		(pin "1"
		)
		(instances
			(project "artix-dc-scm"
				(path ""
					(reference "#PWR0290")
					(unit 1)
				)
			)
		)
	)
	(symbol
		(lib_id "antmicropower:GND")
		(at 345.44 226.06 0)
		(unit 1)
		(exclude_from_sim no)
		(in_bom yes)
		(on_board yes)
		(dnp no)
		(property "Reference" "#PWR0291"
			(at 345.44 232.41 0)
			(effects
				(font
					(size 1.27 1.27)
				)
				(hide yes)
			)
		)
		(property "Value" "GND"
			(at 345.44 229.87 0)
			(effects
				(font
					(size 1.27 1.27)
				)
			)
		)
		(property "Footprint" ""
			(at 345.44 226.06 0)
			(effects
				(font
					(size 1.27 1.27)
				)
				(hide yes)
			)
		)
		(property "Datasheet" ""
			(at 345.44 226.06 0)
			(effects
				(font
					(size 1.27 1.27)
				)
				(hide yes)
			)
		)
		(property "Description" ""
			(at 345.44 226.06 0)
			(effects
				(font
					(size 1.27 1.27)
				)
				(hide yes)
			)
		)
		(property "Author" "Antmicro"
			(at 354.33 233.68 0)
			(effects
				(font
					(size 1.27 1.27)
					(thickness 0.15)
				)
				(justify left bottom)
				(hide yes)
			)
		)
		(property "License" "Apache-2.0"
			(at 354.33 236.22 0)
			(effects
				(font
					(size 1.27 1.27)
					(thickness 0.15)
				)
				(justify left bottom)
				(hide yes)
			)
		)
		(pin "1"
		)
		(instances
			(project "artix-dc-scm"
				(path ""
					(reference "#PWR0291")
					(unit 1)
				)
			)
		)
	)
	(symbol
		(lib_id "antmicropower:GND")
		(at 369.57 40.64 0)
		(unit 1)
		(exclude_from_sim no)
		(in_bom yes)
		(on_board yes)
		(dnp no)
		(property "Reference" "#PWR0303"
			(at 369.57 46.99 0)
			(effects
				(font
					(size 1.27 1.27)
				)
				(hide yes)
			)
		)
		(property "Value" "GND"
			(at 369.57 44.45 0)
			(effects
				(font
					(size 1.27 1.27)
				)
			)
		)
		(property "Footprint" ""
			(at 369.57 40.64 0)
			(effects
				(font
					(size 1.27 1.27)
				)
				(hide yes)
			)
		)
		(property "Datasheet" ""
			(at 369.57 40.64 0)
			(effects
				(font
					(size 1.27 1.27)
				)
				(hide yes)
			)
		)
		(property "Description" ""
			(at 369.57 40.64 0)
			(effects
				(font
					(size 1.27 1.27)
				)
				(hide yes)
			)
		)
		(property "Author" "Antmicro"
			(at 378.46 48.26 0)
			(effects
				(font
					(size 1.27 1.27)
					(thickness 0.15)
				)
				(justify left bottom)
				(hide yes)
			)
		)
		(property "License" "Apache-2.0"
			(at 378.46 50.8 0)
			(effects
				(font
					(size 1.27 1.27)
					(thickness 0.15)
				)
				(justify left bottom)
				(hide yes)
			)
		)
		(pin "1"
		)
		(instances
			(project "artix-dc-scm"
				(path ""
					(reference "#PWR0303")
					(unit 1)
				)
			)
		)
	)
	(symbol
		(lib_id "antmicropower:GND")
		(at 54.61 63.5 0)
		(unit 1)
		(exclude_from_sim no)
		(in_bom yes)
		(on_board yes)
		(dnp no)
		(property "Reference" "#PWR0283"
			(at 54.61 69.85 0)
			(effects
				(font
					(size 1.27 1.27)
				)
				(hide yes)
			)
		)
		(property "Value" "GND"
			(at 54.61 67.31 0)
			(effects
				(font
					(size 1.27 1.27)
				)
			)
		)
		(property "Footprint" ""
			(at 54.61 63.5 0)
			(effects
				(font
					(size 1.27 1.27)
				)
				(hide yes)
			)
		)
		(property "Datasheet" ""
			(at 54.61 63.5 0)
			(effects
				(font
					(size 1.27 1.27)
				)
				(hide yes)
			)
		)
		(property "Description" ""
			(at 54.61 63.5 0)
			(effects
				(font
					(size 1.27 1.27)
				)
				(hide yes)
			)
		)
		(property "Author" "Antmicro"
			(at 63.5 71.12 0)
			(effects
				(font
					(size 1.27 1.27)
					(thickness 0.15)
				)
				(justify left bottom)
				(hide yes)
			)
		)
		(property "License" "Apache-2.0"
			(at 63.5 73.66 0)
			(effects
				(font
					(size 1.27 1.27)
					(thickness 0.15)
				)
				(justify left bottom)
				(hide yes)
			)
		)
		(pin "1"
		)
		(instances
			(project "artix-dc-scm"
				(path ""
					(reference "#PWR0283")
					(unit 1)
				)
			)
		)
	)
	(symbol
		(lib_id "antmicropower:GND")
		(at 369.57 173.99 0)
		(unit 1)
		(exclude_from_sim no)
		(in_bom yes)
		(on_board yes)
		(dnp no)
		(property "Reference" "#PWR0289"
			(at 369.57 180.34 0)
			(effects
				(font
					(size 1.27 1.27)
				)
				(hide yes)
			)
		)
		(property "Value" "GND"
			(at 369.57 177.8 0)
			(effects
				(font
					(size 1.27 1.27)
				)
			)
		)
		(property "Footprint" ""
			(at 369.57 173.99 0)
			(effects
				(font
					(size 1.27 1.27)
				)
				(hide yes)
			)
		)
		(property "Datasheet" ""
			(at 369.57 173.99 0)
			(effects
				(font
					(size 1.27 1.27)
				)
				(hide yes)
			)
		)
		(property "Description" ""
			(at 369.57 173.99 0)
			(effects
				(font
					(size 1.27 1.27)
				)
				(hide yes)
			)
		)
		(property "Author" "Antmicro"
			(at 378.46 181.61 0)
			(effects
				(font
					(size 1.27 1.27)
					(thickness 0.15)
				)
				(justify left bottom)
				(hide yes)
			)
		)
		(property "License" "Apache-2.0"
			(at 378.46 184.15 0)
			(effects
				(font
					(size 1.27 1.27)
					(thickness 0.15)
				)
				(justify left bottom)
				(hide yes)
			)
		)
		(pin "1"
		)
		(instances
			(project "artix-dc-scm"
				(path ""
					(reference "#PWR0289")
					(unit 1)
				)
			)
		)
	)
	(symbol
		(lib_id "antmicropower:GND")
		(at 377.19 129.54 0)
		(unit 1)
		(exclude_from_sim no)
		(in_bom yes)
		(on_board yes)
		(dnp no)
		(property "Reference" "#PWR0300"
			(at 377.19 135.89 0)
			(effects
				(font
					(size 1.27 1.27)
				)
				(hide yes)
			)
		)
		(property "Value" "GND"
			(at 377.19 133.35 0)
			(effects
				(font
					(size 1.27 1.27)
				)
			)
		)
		(property "Footprint" ""
			(at 377.19 129.54 0)
			(effects
				(font
					(size 1.27 1.27)
				)
				(hide yes)
			)
		)
		(property "Datasheet" ""
			(at 377.19 129.54 0)
			(effects
				(font
					(size 1.27 1.27)
				)
				(hide yes)
			)
		)
		(property "Description" ""
			(at 377.19 129.54 0)
			(effects
				(font
					(size 1.27 1.27)
				)
				(hide yes)
			)
		)
		(property "Author" "Antmicro"
			(at 386.08 137.16 0)
			(effects
				(font
					(size 1.27 1.27)
					(thickness 0.15)
				)
				(justify left bottom)
				(hide yes)
			)
		)
		(property "License" "Apache-2.0"
			(at 386.08 139.7 0)
			(effects
				(font
					(size 1.27 1.27)
					(thickness 0.15)
				)
				(justify left bottom)
				(hide yes)
			)
		)
		(pin "1"
		)
		(instances
			(project "artix-dc-scm"
				(path ""
					(reference "#PWR0300")
					(unit 1)
				)
			)
		)
	)
	(symbol
		(lib_id "antmicropower:GND")
		(at 360.68 92.71 0)
		(unit 1)
		(exclude_from_sim no)
		(in_bom yes)
		(on_board yes)
		(dnp no)
		(property "Reference" "#PWR0309"
			(at 360.68 99.06 0)
			(effects
				(font
					(size 1.27 1.27)
				)
				(hide yes)
			)
		)
		(property "Value" "GND"
			(at 360.68 96.52 0)
			(effects
				(font
					(size 1.27 1.27)
				)
			)
		)
		(property "Footprint" ""
			(at 360.68 92.71 0)
			(effects
				(font
					(size 1.27 1.27)
				)
				(hide yes)
			)
		)
		(property "Datasheet" ""
			(at 360.68 92.71 0)
			(effects
				(font
					(size 1.27 1.27)
				)
				(hide yes)
			)
		)
		(property "Description" ""
			(at 360.68 92.71 0)
			(effects
				(font
					(size 1.27 1.27)
				)
				(hide yes)
			)
		)
		(property "Author" "Antmicro"
			(at 369.57 100.33 0)
			(effects
				(font
					(size 1.27 1.27)
					(thickness 0.15)
				)
				(justify left bottom)
				(hide yes)
			)
		)
		(property "License" "Apache-2.0"
			(at 369.57 102.87 0)
			(effects
				(font
					(size 1.27 1.27)
					(thickness 0.15)
				)
				(justify left bottom)
				(hide yes)
			)
		)
		(pin "1"
		)
		(instances
			(project "artix-dc-scm"
				(path ""
					(reference "#PWR0309")
					(unit 1)
				)
			)
		)
	)
	(symbol
		(lib_id "antmicropower:GND")
		(at 360.68 137.16 0)
		(unit 1)
		(exclude_from_sim no)
		(in_bom yes)
		(on_board yes)
		(dnp no)
		(property "Reference" "#PWR0299"
			(at 360.68 143.51 0)
			(effects
				(font
					(size 1.27 1.27)
				)
				(hide yes)
			)
		)
		(property "Value" "GND"
			(at 360.68 140.97 0)
			(effects
				(font
					(size 1.27 1.27)
				)
			)
		)
		(property "Footprint" ""
			(at 360.68 137.16 0)
			(effects
				(font
					(size 1.27 1.27)
				)
				(hide yes)
			)
		)
		(property "Datasheet" ""
			(at 360.68 137.16 0)
			(effects
				(font
					(size 1.27 1.27)
				)
				(hide yes)
			)
		)
		(property "Description" ""
			(at 360.68 137.16 0)
			(effects
				(font
					(size 1.27 1.27)
				)
				(hide yes)
			)
		)
		(property "Author" "Antmicro"
			(at 369.57 144.78 0)
			(effects
				(font
					(size 1.27 1.27)
					(thickness 0.15)
				)
				(justify left bottom)
				(hide yes)
			)
		)
		(property "License" "Apache-2.0"
			(at 369.57 147.32 0)
			(effects
				(font
					(size 1.27 1.27)
					(thickness 0.15)
				)
				(justify left bottom)
				(hide yes)
			)
		)
		(pin "1"
		)
		(instances
			(project "artix-dc-scm"
				(path ""
					(reference "#PWR0299")
					(unit 1)
				)
			)
		)
	)
	(symbol
		(lib_id "antmicroLEDIndicationDiscrete:LED_G_0603_LG_L29K-G2J1-24-Z")
		(at 247.65 93.98 0)
		(unit 1)
		(exclude_from_sim no)
		(in_bom yes)
		(on_board yes)
		(dnp no)
		(fields_autoplaced yes)
		(property "Reference" "D6"
			(at 250.19 83.82 0)
			(effects
				(font
					(size 1.27 1.27)
				)
			)
		)
		(property "Value" "LED_G_0603_LG_L29K-G2J1-24-Z"
			(at 251.46 89.535 0)
			(effects
				(font
					(size 1.27 1.27)
					(thickness 0.15)
				)
				(hide yes)
			)
		)
		(property "Footprint" "antmicro-footprints:LED_0603_1608Metric_G"
			(at 270.51 104.14 0)
			(effects
				(font
					(size 1.27 1.27)
					(thickness 0.15)
				)
				(justify left bottom)
				(hide yes)
			)
		)
		(property "Datasheet" "https://look.ams-osram.com/m/19ee86b3ae0ee95b/original/LG-L29K.pdf"
			(at 270.51 106.68 0)
			(effects
				(font
					(size 1.27 1.27)
					(thickness 0.15)
				)
				(justify left bottom)
				(hide yes)
			)
		)
		(property "Description" "LED, Green, SMD, 0603, 20 mA, 1.7 V, 570 nm"
			(at 247.65 93.98 0)
			(effects
				(font
					(size 1.27 1.27)
				)
				(hide yes)
			)
		)
		(property "MPN" "LG L29K-G2J1-24-Z"
			(at 250.19 86.36 0)
			(effects
				(font
					(size 1.27 1.27)
					(thickness 0.15)
				)
			)
		)
		(property "Manufacturer" "OSRAM"
			(at 270.51 111.76 0)
			(effects
				(font
					(size 1.27 1.27)
					(thickness 0.15)
				)
				(justify left bottom)
				(hide yes)
			)
		)
		(property "Author" "Antmicro"
			(at 270.51 114.3 0)
			(effects
				(font
					(size 1.27 1.27)
					(thickness 0.15)
				)
				(justify left bottom)
				(hide yes)
			)
		)
		(property "License" "Apache-2.0"
			(at 270.51 116.84 0)
			(effects
				(font
					(size 1.27 1.27)
					(thickness 0.15)
				)
				(justify left bottom)
				(hide yes)
			)
		)
		(property "Color" "Green"
			(at 250.19 88.9 0)
			(effects
				(font
					(size 1.27 1.27)
				)
			)
		)
		(pin "1"
		)
		(pin "2"
		)
		(instances
			(project "artix-dc-scm"
				(path ""
					(reference "D6")
					(unit 1)
				)
			)
		)
	)
	(symbol
		(lib_id "antmicropower:PWR_FLAG")
		(at 93.98 54.61 0)
		(unit 1)
		(exclude_from_sim no)
		(in_bom yes)
		(on_board yes)
		(dnp no)
		(fields_autoplaced yes)
		(property "Reference" "#FLG0102"
			(at 93.98 52.705 0)
			(effects
				(font
					(size 1.27 1.27)
				)
				(hide yes)
			)
		)
		(property "Value" "PWR_FLAG"
			(at 93.98 48.895 0)
			(effects
				(font
					(size 1.27 1.27)
				)
			)
		)
		(property "Footprint" ""
			(at 93.98 54.61 0)
			(effects
				(font
					(size 1.27 1.27)
				)
				(hide yes)
			)
		)
		(property "Datasheet" ""
			(at 93.98 54.61 0)
			(effects
				(font
					(size 1.27 1.27)
				)
				(hide yes)
			)
		)
		(property "Description" ""
			(at 93.98 54.61 0)
			(effects
				(font
					(size 1.27 1.27)
				)
				(hide yes)
			)
		)
		(pin "1"
		)
		(instances
			(project "artix-dc-scm"
				(path ""
					(reference "#FLG0102")
					(unit 1)
				)
			)
		)
	)
	(symbol
		(lib_id "antmicroLEDIndicationDiscrete:LED_G_0603_LG_L29K-G2J1-24-Z")
		(at 247.65 34.29 0)
		(unit 1)
		(exclude_from_sim no)
		(in_bom yes)
		(on_board yes)
		(dnp no)
		(fields_autoplaced yes)
		(property "Reference" "D14"
			(at 250.19 24.13 0)
			(effects
				(font
					(size 1.27 1.27)
				)
			)
		)
		(property "Value" "LED_G_0603_LG_L29K-G2J1-24-Z"
			(at 251.46 29.21 0)
			(effects
				(font
					(size 1.27 1.27)
					(thickness 0.15)
				)
				(hide yes)
			)
		)
		(property "Footprint" "antmicro-footprints:LED_0603_1608Metric_G"
			(at 270.51 44.45 0)
			(effects
				(font
					(size 1.27 1.27)
					(thickness 0.15)
				)
				(justify left bottom)
				(hide yes)
			)
		)
		(property "Datasheet" "https://look.ams-osram.com/m/19ee86b3ae0ee95b/original/LG-L29K.pdf"
			(at 270.51 46.99 0)
			(effects
				(font
					(size 1.27 1.27)
					(thickness 0.15)
				)
				(justify left bottom)
				(hide yes)
			)
		)
		(property "Description" "LED, Green, SMD, 0603, 20 mA, 1.7 V, 570 nm"
			(at 247.65 34.29 0)
			(effects
				(font
					(size 1.27 1.27)
				)
				(hide yes)
			)
		)
		(property "MPN" "LG L29K-G2J1-24-Z"
			(at 250.19 26.67 0)
			(effects
				(font
					(size 1.27 1.27)
					(thickness 0.15)
				)
			)
		)
		(property "Manufacturer" "OSRAM"
			(at 270.51 52.07 0)
			(effects
				(font
					(size 1.27 1.27)
					(thickness 0.15)
				)
				(justify left bottom)
				(hide yes)
			)
		)
		(property "Author" "Antmicro"
			(at 270.51 54.61 0)
			(effects
				(font
					(size 1.27 1.27)
					(thickness 0.15)
				)
				(justify left bottom)
				(hide yes)
			)
		)
		(property "License" "Apache-2.0"
			(at 270.51 57.15 0)
			(effects
				(font
					(size 1.27 1.27)
					(thickness 0.15)
				)
				(justify left bottom)
				(hide yes)
			)
		)
		(property "Color" "Green"
			(at 250.19 29.21 0)
			(effects
				(font
					(size 1.27 1.27)
				)
			)
		)
		(pin "1"
		)
		(pin "2"
		)
		(instances
			(project "artix-dc-scm"
				(path ""
					(reference "D14")
					(unit 1)
				)
			)
		)
	)
	(symbol
		(lib_id "antmicropower:GND")
		(at 369.57 129.54 0)
		(unit 1)
		(exclude_from_sim no)
		(in_bom yes)
		(on_board yes)
		(dnp no)
		(property "Reference" "#PWR0301"
			(at 369.57 135.89 0)
			(effects
				(font
					(size 1.27 1.27)
				)
				(hide yes)
			)
		)
		(property "Value" "GND"
			(at 369.57 133.35 0)
			(effects
				(font
					(size 1.27 1.27)
				)
			)
		)
		(property "Footprint" ""
			(at 369.57 129.54 0)
			(effects
				(font
					(size 1.27 1.27)
				)
				(hide yes)
			)
		)
		(property "Datasheet" ""
			(at 369.57 129.54 0)
			(effects
				(font
					(size 1.27 1.27)
				)
				(hide yes)
			)
		)
		(property "Description" ""
			(at 369.57 129.54 0)
			(effects
				(font
					(size 1.27 1.27)
				)
				(hide yes)
			)
		)
		(property "Author" "Antmicro"
			(at 378.46 137.16 0)
			(effects
				(font
					(size 1.27 1.27)
					(thickness 0.15)
				)
				(justify left bottom)
				(hide yes)
			)
		)
		(property "License" "Apache-2.0"
			(at 378.46 139.7 0)
			(effects
				(font
					(size 1.27 1.27)
					(thickness 0.15)
				)
				(justify left bottom)
				(hide yes)
			)
		)
		(pin "1"
		)
		(instances
			(project "artix-dc-scm"
				(path ""
					(reference "#PWR0301")
					(unit 1)
				)
			)
		)
	)
	(symbol
		(lib_id "antmicropower:GND")
		(at 377.19 40.64 0)
		(unit 1)
		(exclude_from_sim no)
		(in_bom yes)
		(on_board yes)
		(dnp no)
		(property "Reference" "#PWR0304"
			(at 377.19 46.99 0)
			(effects
				(font
					(size 1.27 1.27)
				)
				(hide yes)
			)
		)
		(property "Value" "GND"
			(at 377.19 44.45 0)
			(effects
				(font
					(size 1.27 1.27)
				)
			)
		)
		(property "Footprint" ""
			(at 377.19 40.64 0)
			(effects
				(font
					(size 1.27 1.27)
				)
				(hide yes)
			)
		)
		(property "Datasheet" ""
			(at 377.19 40.64 0)
			(effects
				(font
					(size 1.27 1.27)
				)
				(hide yes)
			)
		)
		(property "Description" ""
			(at 377.19 40.64 0)
			(effects
				(font
					(size 1.27 1.27)
				)
				(hide yes)
			)
		)
		(property "Author" "Antmicro"
			(at 386.08 48.26 0)
			(effects
				(font
					(size 1.27 1.27)
					(thickness 0.15)
				)
				(justify left bottom)
				(hide yes)
			)
		)
		(property "License" "Apache-2.0"
			(at 386.08 50.8 0)
			(effects
				(font
					(size 1.27 1.27)
					(thickness 0.15)
				)
				(justify left bottom)
				(hide yes)
			)
		)
		(pin "1"
		)
		(instances
			(project "artix-dc-scm"
				(path ""
					(reference "#PWR0304")
					(unit 1)
				)
			)
		)
	)
	(symbol
		(lib_id "antmicropower:GND")
		(at 165.1 87.63 0)
		(unit 1)
		(exclude_from_sim no)
		(in_bom yes)
		(on_board yes)
		(dnp no)
		(property "Reference" "#PWR0312"
			(at 165.1 93.98 0)
			(effects
				(font
					(size 1.27 1.27)
				)
				(hide yes)
			)
		)
		(property "Value" "GND"
			(at 165.1 91.44 0)
			(effects
				(font
					(size 1.27 1.27)
				)
			)
		)
		(property "Footprint" ""
			(at 165.1 87.63 0)
			(effects
				(font
					(size 1.27 1.27)
				)
				(hide yes)
			)
		)
		(property "Datasheet" ""
			(at 165.1 87.63 0)
			(effects
				(font
					(size 1.27 1.27)
				)
				(hide yes)
			)
		)
		(property "Description" ""
			(at 165.1 87.63 0)
			(effects
				(font
					(size 1.27 1.27)
				)
				(hide yes)
			)
		)
		(property "Author" "Antmicro"
			(at 173.99 95.25 0)
			(effects
				(font
					(size 1.27 1.27)
					(thickness 0.15)
				)
				(justify left bottom)
				(hide yes)
			)
		)
		(property "License" "Apache-2.0"
			(at 173.99 97.79 0)
			(effects
				(font
					(size 1.27 1.27)
					(thickness 0.15)
				)
				(justify left bottom)
				(hide yes)
			)
		)
		(pin "1"
		)
		(instances
			(project "artix-dc-scm"
				(path ""
					(reference "#PWR0312")
					(unit 1)
				)
			)
		)
	)
	(symbol
		(lib_id "antmicropower:GND")
		(at 360.68 226.06 0)
		(unit 1)
		(exclude_from_sim no)
		(in_bom yes)
		(on_board yes)
		(dnp no)
		(property "Reference" "#PWR0292"
			(at 360.68 232.41 0)
			(effects
				(font
					(size 1.27 1.27)
				)
				(hide yes)
			)
		)
		(property "Value" "GND"
			(at 360.68 229.87 0)
			(effects
				(font
					(size 1.27 1.27)
				)
			)
		)
		(property "Footprint" ""
			(at 360.68 226.06 0)
			(effects
				(font
					(size 1.27 1.27)
				)
				(hide yes)
			)
		)
		(property "Datasheet" ""
			(at 360.68 226.06 0)
			(effects
				(font
					(size 1.27 1.27)
				)
				(hide yes)
			)
		)
		(property "Description" ""
			(at 360.68 226.06 0)
			(effects
				(font
					(size 1.27 1.27)
				)
				(hide yes)
			)
		)
		(property "Author" "Antmicro"
			(at 369.57 233.68 0)
			(effects
				(font
					(size 1.27 1.27)
					(thickness 0.15)
				)
				(justify left bottom)
				(hide yes)
			)
		)
		(property "License" "Apache-2.0"
			(at 369.57 236.22 0)
			(effects
				(font
					(size 1.27 1.27)
					(thickness 0.15)
				)
				(justify left bottom)
				(hide yes)
			)
		)
		(pin "1"
		)
		(instances
			(project "artix-dc-scm"
				(path ""
					(reference "#PWR0292")
					(unit 1)
				)
			)
		)
	)
	(symbol
		(lib_id "antmicropower:GND")
		(at 80.01 93.98 0)
		(mirror y)
		(unit 1)
		(exclude_from_sim no)
		(in_bom yes)
		(on_board yes)
		(dnp no)
		(property "Reference" "#PWR0287"
			(at 80.01 100.33 0)
			(effects
				(font
					(size 1.27 1.27)
				)
				(hide yes)
			)
		)
		(property "Value" "GND"
			(at 80.01 97.79 0)
			(effects
				(font
					(size 1.27 1.27)
				)
			)
		)
		(property "Footprint" ""
			(at 80.01 93.98 0)
			(effects
				(font
					(size 1.27 1.27)
				)
				(hide yes)
			)
		)
		(property "Datasheet" ""
			(at 80.01 93.98 0)
			(effects
				(font
					(size 1.27 1.27)
				)
				(hide yes)
			)
		)
		(property "Description" ""
			(at 80.01 93.98 0)
			(effects
				(font
					(size 1.27 1.27)
				)
				(hide yes)
			)
		)
		(property "Author" "Antmicro"
			(at 71.12 101.6 0)
			(effects
				(font
					(size 1.27 1.27)
					(thickness 0.15)
				)
				(justify left bottom)
				(hide yes)
			)
		)
		(property "License" "Apache-2.0"
			(at 71.12 104.14 0)
			(effects
				(font
					(size 1.27 1.27)
					(thickness 0.15)
				)
				(justify left bottom)
				(hide yes)
			)
		)
		(pin "1"
		)
		(instances
			(project "artix-dc-scm"
				(path ""
					(reference "#PWR0287")
					(unit 1)
				)
			)
		)
	)
	(symbol
		(lib_id "antmicroDiodesRectifiersSingle:PDS760")
		(at 139.7 83.82 0)
		(mirror x)
		(unit 1)
		(exclude_from_sim no)
		(in_bom yes)
		(on_board yes)
		(dnp no)
		(property "Reference" "D3"
			(at 142.24 86.36 0)
			(effects
				(font
					(size 1.27 1.27)
				)
			)
		)
		(property "Value" "PDS760"
			(at 142.24 88.9 0)
			(effects
				(font
					(size 1.27 1.27)
					(thickness 0.15)
				)
			)
		)
		(property "Footprint" "antmicro-footprints:PowerDI5"
			(at 162.56 73.66 0)
			(effects
				(font
					(size 1.27 1.27)
					(thickness 0.15)
				)
				(justify left bottom)
				(hide yes)
			)
		)
		(property "Datasheet" "https://www.diodes.com/assets/Datasheets/ds30470.pdf"
			(at 162.56 71.12 0)
			(effects
				(font
					(size 1.27 1.27)
					(thickness 0.15)
				)
				(justify left bottom)
				(hide yes)
			)
		)
		(property "Description" "Schottky Rectifier, POWERDI®, 60 V, 7 A, Single, PowerDI 5, 2 Pins, 620 mV"
			(at 139.7 83.82 0)
			(effects
				(font
					(size 1.27 1.27)
				)
				(hide yes)
			)
		)
		(property "Manufacturer" "Diodes Incorporated"
			(at 162.56 68.58 0)
			(effects
				(font
					(size 1.27 1.27)
					(thickness 0.15)
				)
				(justify left bottom)
				(hide yes)
			)
		)
		(property "MPN" "PDS760-13"
			(at 162.56 66.04 0)
			(effects
				(font
					(size 1.27 1.27)
					(thickness 0.15)
				)
				(justify left bottom)
				(hide yes)
			)
		)
		(property "Author" "Antmicro"
			(at 162.56 63.5 0)
			(effects
				(font
					(size 1.27 1.27)
					(thickness 0.15)
				)
				(justify left bottom)
				(hide yes)
			)
		)
		(property "License" "Apache-2.0"
			(at 162.56 60.96 0)
			(effects
				(font
					(size 1.27 1.27)
					(thickness 0.15)
				)
				(justify left bottom)
				(hide yes)
			)
		)
		(pin "2"
		)
		(pin "1"
		)
		(instances
			(project "artix-dc-scm"
				(path ""
					(reference "D3")
					(unit 1)
				)
			)
		)
	)
	(symbol
		(lib_id "antmicropower:GND")
		(at 360.68 48.26 0)
		(unit 1)
		(exclude_from_sim no)
		(in_bom yes)
		(on_board yes)
		(dnp no)
		(property "Reference" "#PWR0302"
			(at 360.68 54.61 0)
			(effects
				(font
					(size 1.27 1.27)
				)
				(hide yes)
			)
		)
		(property "Value" "GND"
			(at 360.68 52.07 0)
			(effects
				(font
					(size 1.27 1.27)
				)
			)
		)
		(property "Footprint" ""
			(at 360.68 48.26 0)
			(effects
				(font
					(size 1.27 1.27)
				)
				(hide yes)
			)
		)
		(property "Datasheet" ""
			(at 360.68 48.26 0)
			(effects
				(font
					(size 1.27 1.27)
				)
				(hide yes)
			)
		)
		(property "Description" ""
			(at 360.68 48.26 0)
			(effects
				(font
					(size 1.27 1.27)
				)
				(hide yes)
			)
		)
		(property "Author" "Antmicro"
			(at 369.57 55.88 0)
			(effects
				(font
					(size 1.27 1.27)
					(thickness 0.15)
				)
				(justify left bottom)
				(hide yes)
			)
		)
		(property "License" "Apache-2.0"
			(at 369.57 58.42 0)
			(effects
				(font
					(size 1.27 1.27)
					(thickness 0.15)
				)
				(justify left bottom)
				(hide yes)
			)
		)
		(pin "1"
		)
		(instances
			(project "artix-dc-scm"
				(path ""
					(reference "#PWR0302")
					(unit 1)
				)
			)
		)
	)
	(symbol
		(lib_id "antmicropower:PWR_FLAG")
		(at 393.7 34.29 0)
		(unit 1)
		(exclude_from_sim no)
		(in_bom yes)
		(on_board yes)
		(dnp no)
		(property "Reference" "#FLG0120"
			(at 393.7 32.385 0)
			(effects
				(font
					(size 1.27 1.27)
				)
				(hide yes)
			)
		)
		(property "Value" "PWR_FLAG"
			(at 393.7 30.48 0)
			(effects
				(font
					(size 1.27 1.27)
				)
			)
		)
		(property "Footprint" ""
			(at 393.7 34.29 0)
			(effects
				(font
					(size 1.27 1.27)
				)
				(hide yes)
			)
		)
		(property "Datasheet" ""
			(at 393.7 34.29 0)
			(effects
				(font
					(size 1.27 1.27)
				)
				(hide yes)
			)
		)
		(property "Description" ""
			(at 393.7 34.29 0)
			(effects
				(font
					(size 1.27 1.27)
				)
				(hide yes)
			)
		)
		(pin "1"
		)
		(instances
			(project "artix-dc-scm"
				(path ""
					(reference "#FLG0120")
					(unit 1)
				)
			)
		)
	)
	(symbol
		(lib_id "antmicropower:GND")
		(at 316.23 119.38 0)
		(unit 1)
		(exclude_from_sim no)
		(in_bom yes)
		(on_board yes)
		(dnp no)
		(property "Reference" "#PWR0306"
			(at 316.23 125.73 0)
			(effects
				(font
					(size 1.27 1.27)
				)
				(hide yes)
			)
		)
		(property "Value" "GND"
			(at 316.23 123.19 0)
			(effects
				(font
					(size 1.27 1.27)
				)
			)
		)
		(property "Footprint" ""
			(at 316.23 119.38 0)
			(effects
				(font
					(size 1.27 1.27)
				)
				(hide yes)
			)
		)
		(property "Datasheet" ""
			(at 316.23 119.38 0)
			(effects
				(font
					(size 1.27 1.27)
				)
				(hide yes)
			)
		)
		(property "Description" ""
			(at 316.23 119.38 0)
			(effects
				(font
					(size 1.27 1.27)
				)
				(hide yes)
			)
		)
		(property "Author" "Antmicro"
			(at 325.12 127 0)
			(effects
				(font
					(size 1.27 1.27)
					(thickness 0.15)
				)
				(justify left bottom)
				(hide yes)
			)
		)
		(property "License" "Apache-2.0"
			(at 325.12 129.54 0)
			(effects
				(font
					(size 1.27 1.27)
					(thickness 0.15)
				)
				(justify left bottom)
				(hide yes)
			)
		)
		(pin "1"
		)
		(instances
			(project "artix-dc-scm"
				(path ""
					(reference "#PWR0306")
					(unit 1)
				)
			)
		)
	)
	(symbol
		(lib_id "antmicropower:PWR_FLAG")
		(at 393.7 167.64 0)
		(unit 1)
		(exclude_from_sim no)
		(in_bom yes)
		(on_board yes)
		(dnp no)
		(property "Reference" "#FLG0119"
			(at 393.7 165.735 0)
			(effects
				(font
					(size 1.27 1.27)
				)
				(hide yes)
			)
		)
		(property "Value" "PWR_FLAG"
			(at 393.7 163.83 0)
			(effects
				(font
					(size 1.27 1.27)
				)
			)
		)
		(property "Footprint" ""
			(at 393.7 167.64 0)
			(effects
				(font
					(size 1.27 1.27)
				)
				(hide yes)
			)
		)
		(property "Datasheet" ""
			(at 393.7 167.64 0)
			(effects
				(font
					(size 1.27 1.27)
				)
				(hide yes)
			)
		)
		(property "Description" ""
			(at 393.7 167.64 0)
			(effects
				(font
					(size 1.27 1.27)
				)
				(hide yes)
			)
		)
		(pin "1"
		)
		(instances
			(project "artix-dc-scm"
				(path ""
					(reference "#FLG0119")
					(unit 1)
				)
			)
		)
	)
	(symbol
		(lib_id "antmicroResistors0402:R_200k_0402")
		(at 360.68 85.09 90)
		(unit 1)
		(exclude_from_sim no)
		(in_bom yes)
		(on_board yes)
		(dnp no)
		(property "Reference" "R75"
			(at 361.95 81.28 90)
			(effects
				(font
					(size 1.27 1.27)
					(thickness 0.15)
				)
				(justify right)
			)
		)
		(property "Value" "R_200k_0402"
			(at 373.38 64.77 0)
			(effects
				(font
					(size 1.27 1.27)
					(thickness 0.15)
				)
				(justify left bottom)
				(hide yes)
			)
		)
		(property "Footprint" "antmicro-footprints:R_0402_1005Metric"
			(at 375.92 64.77 0)
			(effects
				(font
					(size 1.27 1.27)
					(thickness 0.15)
				)
				(justify left bottom)
				(hide yes)
			)
		)
		(property "Datasheet" "https://www.bourns.com/docs/product-datasheets/cr.pdf"
			(at 378.46 64.77 0)
			(effects
				(font
					(size 1.27 1.27)
					(thickness 0.15)
				)
				(justify left bottom)
				(hide yes)
			)
		)
		(property "Description" "SMD Chip Resistor, 200 kohm, ± 1%, 62.5 mW, 0402 [1005 Metric], Thick Film, General Purpose"
			(at 360.68 85.09 0)
			(effects
				(font
					(size 1.27 1.27)
				)
				(hide yes)
			)
		)
		(property "MPN" "CR0402-FX-2003GLF"
			(at 381 64.77 0)
			(effects
				(font
					(size 1.27 1.27)
					(thickness 0.15)
				)
				(justify left bottom)
				(hide yes)
			)
		)
		(property "Manufacturer" "Bourns"
			(at 383.54 64.77 0)
			(effects
				(font
					(size 1.27 1.27)
					(thickness 0.15)
				)
				(justify left bottom)
				(hide yes)
			)
		)
		(property "License" "Apache-2.0"
			(at 386.08 64.77 0)
			(effects
				(font
					(size 1.27 1.27)
					(thickness 0.15)
				)
				(justify left bottom)
				(hide yes)
			)
		)
		(property "Author" "Antmicro"
			(at 388.62 64.77 0)
			(effects
				(font
					(size 1.27 1.27)
					(thickness 0.15)
				)
				(justify left bottom)
				(hide yes)
			)
		)
		(property "Val" "200k"
			(at 361.95 83.82 90)
			(effects
				(font
					(size 1.27 1.27)
					(thickness 0.15)
				)
				(justify right)
			)
		)
		(property "Tolerance" "1%"
			(at 370.84 64.77 0)
			(effects
				(font
					(size 1.27 1.27)
				)
				(justify left bottom)
				(hide yes)
			)
		)
		(pin "1"
		)
		(pin "2"
		)
		(instances
			(project "artix-dc-scm"
				(path ""
					(reference "R75")
					(unit 1)
				)
			)
		)
	)
	(symbol
		(lib_id "antmicroLEDIndicationDiscrete:LED_G_0603_LG_L29K-G2J1-24-Z")
		(at 247.65 62.23 0)
		(unit 1)
		(exclude_from_sim no)
		(in_bom yes)
		(on_board yes)
		(dnp no)
		(fields_autoplaced yes)
		(property "Reference" "D8"
			(at 250.19 52.07 0)
			(effects
				(font
					(size 1.27 1.27)
				)
			)
		)
		(property "Value" "LED_G_0603_LG_L29K-G2J1-24-Z"
			(at 251.46 57.15 0)
			(effects
				(font
					(size 1.27 1.27)
					(thickness 0.15)
				)
				(hide yes)
			)
		)
		(property "Footprint" "antmicro-footprints:LED_0603_1608Metric_G"
			(at 270.51 72.39 0)
			(effects
				(font
					(size 1.27 1.27)
					(thickness 0.15)
				)
				(justify left bottom)
				(hide yes)
			)
		)
		(property "Datasheet" "https://look.ams-osram.com/m/19ee86b3ae0ee95b/original/LG-L29K.pdf"
			(at 270.51 74.93 0)
			(effects
				(font
					(size 1.27 1.27)
					(thickness 0.15)
				)
				(justify left bottom)
				(hide yes)
			)
		)
		(property "Description" "LED, Green, SMD, 0603, 20 mA, 1.7 V, 570 nm"
			(at 247.65 62.23 0)
			(effects
				(font
					(size 1.27 1.27)
				)
				(hide yes)
			)
		)
		(property "MPN" "LG L29K-G2J1-24-Z"
			(at 250.19 54.61 0)
			(effects
				(font
					(size 1.27 1.27)
					(thickness 0.15)
				)
			)
		)
		(property "Manufacturer" "OSRAM"
			(at 270.51 80.01 0)
			(effects
				(font
					(size 1.27 1.27)
					(thickness 0.15)
				)
				(justify left bottom)
				(hide yes)
			)
		)
		(property "Author" "Antmicro"
			(at 270.51 82.55 0)
			(effects
				(font
					(size 1.27 1.27)
					(thickness 0.15)
				)
				(justify left bottom)
				(hide yes)
			)
		)
		(property "License" "Apache-2.0"
			(at 270.51 85.09 0)
			(effects
				(font
					(size 1.27 1.27)
					(thickness 0.15)
				)
				(justify left bottom)
				(hide yes)
			)
		)
		(property "Color" "Green"
			(at 250.19 57.15 0)
			(effects
				(font
					(size 1.27 1.27)
				)
			)
		)
		(pin "1"
		)
		(pin "2"
		)
		(instances
			(project "artix-dc-scm"
				(path ""
					(reference "D8")
					(unit 1)
				)
			)
		)
	)
	(symbol
		(lib_id "antmicroLEDIndicationDiscrete:LED_G_0603_LG_L29K-G2J1-24-Z")
		(at 247.65 124.46 0)
		(unit 1)
		(exclude_from_sim no)
		(in_bom yes)
		(on_board yes)
		(dnp no)
		(fields_autoplaced yes)
		(property "Reference" "D7"
			(at 250.19 114.3 0)
			(effects
				(font
					(size 1.27 1.27)
				)
			)
		)
		(property "Value" "LED_G_0603_LG_L29K-G2J1-24-Z"
			(at 251.46 119.38 0)
			(effects
				(font
					(size 1.27 1.27)
					(thickness 0.15)
				)
				(hide yes)
			)
		)
		(property "Footprint" "antmicro-footprints:LED_0603_1608Metric_G"
			(at 270.51 134.62 0)
			(effects
				(font
					(size 1.27 1.27)
					(thickness 0.15)
				)
				(justify left bottom)
				(hide yes)
			)
		)
		(property "Datasheet" "https://look.ams-osram.com/m/19ee86b3ae0ee95b/original/LG-L29K.pdf"
			(at 270.51 137.16 0)
			(effects
				(font
					(size 1.27 1.27)
					(thickness 0.15)
				)
				(justify left bottom)
				(hide yes)
			)
		)
		(property "Description" "LED, Green, SMD, 0603, 20 mA, 1.7 V, 570 nm"
			(at 247.65 124.46 0)
			(effects
				(font
					(size 1.27 1.27)
				)
				(hide yes)
			)
		)
		(property "MPN" "LG L29K-G2J1-24-Z"
			(at 250.19 116.84 0)
			(effects
				(font
					(size 1.27 1.27)
					(thickness 0.15)
				)
			)
		)
		(property "Manufacturer" "OSRAM"
			(at 270.51 142.24 0)
			(effects
				(font
					(size 1.27 1.27)
					(thickness 0.15)
				)
				(justify left bottom)
				(hide yes)
			)
		)
		(property "Author" "Antmicro"
			(at 270.51 144.78 0)
			(effects
				(font
					(size 1.27 1.27)
					(thickness 0.15)
				)
				(justify left bottom)
				(hide yes)
			)
		)
		(property "License" "Apache-2.0"
			(at 270.51 147.32 0)
			(effects
				(font
					(size 1.27 1.27)
					(thickness 0.15)
				)
				(justify left bottom)
				(hide yes)
			)
		)
		(property "Color" "Green"
			(at 250.19 119.38 0)
			(effects
				(font
					(size 1.27 1.27)
				)
			)
		)
		(pin "1"
		)
		(pin "2"
		)
		(instances
			(project "artix-dc-scm"
				(path ""
					(reference "D7")
					(unit 1)
				)
			)
		)
	)
	(symbol
		(lib_id "antmicropower:GND")
		(at 44.45 63.5 0)
		(unit 1)
		(exclude_from_sim no)
		(in_bom yes)
		(on_board yes)
		(dnp no)
		(property "Reference" "#PWR0285"
			(at 44.45 69.85 0)
			(effects
				(font
					(size 1.27 1.27)
				)
				(hide yes)
			)
		)
		(property "Value" "GND"
			(at 44.45 67.31 0)
			(effects
				(font
					(size 1.27 1.27)
				)
			)
		)
		(property "Footprint" ""
			(at 44.45 63.5 0)
			(effects
				(font
					(size 1.27 1.27)
				)
				(hide yes)
			)
		)
		(property "Datasheet" ""
			(at 44.45 63.5 0)
			(effects
				(font
					(size 1.27 1.27)
				)
				(hide yes)
			)
		)
		(property "Description" ""
			(at 44.45 63.5 0)
			(effects
				(font
					(size 1.27 1.27)
				)
				(hide yes)
			)
		)
		(property "Author" "Antmicro"
			(at 53.34 71.12 0)
			(effects
				(font
					(size 1.27 1.27)
					(thickness 0.15)
				)
				(justify left bottom)
				(hide yes)
			)
		)
		(property "License" "Apache-2.0"
			(at 53.34 73.66 0)
			(effects
				(font
					(size 1.27 1.27)
					(thickness 0.15)
				)
				(justify left bottom)
				(hide yes)
			)
		)
		(pin "1"
		)
		(instances
			(project "artix-dc-scm"
				(path ""
					(reference "#PWR0285")
					(unit 1)
				)
			)
		)
	)
	(symbol
		(lib_id "antmicroLEDIndicationDiscrete:LED_G_0603_LG_L29K-G2J1-24-Z")
		(at 247.65 157.48 0)
		(unit 1)
		(exclude_from_sim no)
		(in_bom yes)
		(on_board yes)
		(dnp no)
		(fields_autoplaced yes)
		(property "Reference" "D4"
			(at 250.19 147.32 0)
			(effects
				(font
					(size 1.27 1.27)
				)
			)
		)
		(property "Value" "LED_G_0603_LG_L29K-G2J1-24-Z"
			(at 251.46 153.035 0)
			(effects
				(font
					(size 1.27 1.27)
					(thickness 0.15)
				)
				(hide yes)
			)
		)
		(property "Footprint" "antmicro-footprints:LED_0603_1608Metric_G"
			(at 270.51 167.64 0)
			(effects
				(font
					(size 1.27 1.27)
					(thickness 0.15)
				)
				(justify left bottom)
				(hide yes)
			)
		)
		(property "Datasheet" "https://look.ams-osram.com/m/19ee86b3ae0ee95b/original/LG-L29K.pdf"
			(at 270.51 170.18 0)
			(effects
				(font
					(size 1.27 1.27)
					(thickness 0.15)
				)
				(justify left bottom)
				(hide yes)
			)
		)
		(property "Description" "LED, Green, SMD, 0603, 20 mA, 1.7 V, 570 nm"
			(at 247.65 157.48 0)
			(effects
				(font
					(size 1.27 1.27)
				)
				(hide yes)
			)
		)
		(property "MPN" "LG L29K-G2J1-24-Z"
			(at 250.19 149.86 0)
			(effects
				(font
					(size 1.27 1.27)
					(thickness 0.15)
				)
			)
		)
		(property "Manufacturer" "OSRAM"
			(at 270.51 175.26 0)
			(effects
				(font
					(size 1.27 1.27)
					(thickness 0.15)
				)
				(justify left bottom)
				(hide yes)
			)
		)
		(property "Author" "Antmicro"
			(at 270.51 177.8 0)
			(effects
				(font
					(size 1.27 1.27)
					(thickness 0.15)
				)
				(justify left bottom)
				(hide yes)
			)
		)
		(property "License" "Apache-2.0"
			(at 270.51 180.34 0)
			(effects
				(font
					(size 1.27 1.27)
					(thickness 0.15)
				)
				(justify left bottom)
				(hide yes)
			)
		)
		(property "Color" "Green"
			(at 250.19 152.4 0)
			(effects
				(font
					(size 1.27 1.27)
				)
			)
		)
		(pin "1"
		)
		(pin "2"
		)
		(instances
			(project "artix-dc-scm"
				(path ""
					(reference "D4")
					(unit 1)
				)
			)
		)
	)
	(symbol
		(lib_id "antmicropower:GND")
		(at 345.44 137.16 0)
		(unit 1)
		(exclude_from_sim no)
		(in_bom yes)
		(on_board yes)
		(dnp no)
		(property "Reference" "#PWR0297"
			(at 345.44 143.51 0)
			(effects
				(font
					(size 1.27 1.27)
				)
				(hide yes)
			)
		)
		(property "Value" "GND"
			(at 345.44 140.97 0)
			(effects
				(font
					(size 1.27 1.27)
				)
			)
		)
		(property "Footprint" ""
			(at 345.44 137.16 0)
			(effects
				(font
					(size 1.27 1.27)
				)
				(hide yes)
			)
		)
		(property "Datasheet" ""
			(at 345.44 137.16 0)
			(effects
				(font
					(size 1.27 1.27)
				)
				(hide yes)
			)
		)
		(property "Description" ""
			(at 345.44 137.16 0)
			(effects
				(font
					(size 1.27 1.27)
				)
				(hide yes)
			)
		)
		(property "Author" "Antmicro"
			(at 354.33 144.78 0)
			(effects
				(font
					(size 1.27 1.27)
					(thickness 0.15)
				)
				(justify left bottom)
				(hide yes)
			)
		)
		(property "License" "Apache-2.0"
			(at 354.33 147.32 0)
			(effects
				(font
					(size 1.27 1.27)
					(thickness 0.15)
				)
				(justify left bottom)
				(hide yes)
			)
		)
		(pin "1"
		)
		(instances
			(project "artix-dc-scm"
				(path ""
					(reference "#PWR0297")
					(unit 1)
				)
			)
		)
	)
	(symbol
		(lib_id "antmicropower:GND")
		(at 369.57 85.09 0)
		(unit 1)
		(exclude_from_sim no)
		(in_bom yes)
		(on_board yes)
		(dnp no)
		(property "Reference" "#PWR0311"
			(at 369.57 91.44 0)
			(effects
				(font
					(size 1.27 1.27)
				)
				(hide yes)
			)
		)
		(property "Value" "GND"
			(at 369.57 88.9 0)
			(effects
				(font
					(size 1.27 1.27)
				)
			)
		)
		(property "Footprint" ""
			(at 369.57 85.09 0)
			(effects
				(font
					(size 1.27 1.27)
				)
				(hide yes)
			)
		)
		(property "Datasheet" ""
			(at 369.57 85.09 0)
			(effects
				(font
					(size 1.27 1.27)
				)
				(hide yes)
			)
		)
		(property "Description" ""
			(at 369.57 85.09 0)
			(effects
				(font
					(size 1.27 1.27)
				)
				(hide yes)
			)
		)
		(property "Author" "Antmicro"
			(at 378.46 92.71 0)
			(effects
				(font
					(size 1.27 1.27)
					(thickness 0.15)
				)
				(justify left bottom)
				(hide yes)
			)
		)
		(property "License" "Apache-2.0"
			(at 378.46 95.25 0)
			(effects
				(font
					(size 1.27 1.27)
					(thickness 0.15)
				)
				(justify left bottom)
				(hide yes)
			)
		)
		(pin "1"
		)
		(instances
			(project "artix-dc-scm"
				(path ""
					(reference "#PWR0311")
					(unit 1)
				)
			)
		)
	)
	(symbol
		(lib_id "antmicropower:GND")
		(at 345.44 181.61 0)
		(unit 1)
		(exclude_from_sim no)
		(in_bom yes)
		(on_board yes)
		(dnp no)
		(property "Reference" "#PWR0295"
			(at 345.44 187.96 0)
			(effects
				(font
					(size 1.27 1.27)
				)
				(hide yes)
			)
		)
		(property "Value" "GND"
			(at 345.44 185.42 0)
			(effects
				(font
					(size 1.27 1.27)
				)
			)
		)
		(property "Footprint" ""
			(at 345.44 181.61 0)
			(effects
				(font
					(size 1.27 1.27)
				)
				(hide yes)
			)
		)
		(property "Datasheet" ""
			(at 345.44 181.61 0)
			(effects
				(font
					(size 1.27 1.27)
				)
				(hide yes)
			)
		)
		(property "Description" ""
			(at 345.44 181.61 0)
			(effects
				(font
					(size 1.27 1.27)
				)
				(hide yes)
			)
		)
		(property "Author" "Antmicro"
			(at 354.33 189.23 0)
			(effects
				(font
					(size 1.27 1.27)
					(thickness 0.15)
				)
				(justify left bottom)
				(hide yes)
			)
		)
		(property "License" "Apache-2.0"
			(at 354.33 191.77 0)
			(effects
				(font
					(size 1.27 1.27)
					(thickness 0.15)
				)
				(justify left bottom)
				(hide yes)
			)
		)
		(pin "1"
		)
		(instances
			(project "artix-dc-scm"
				(path ""
					(reference "#PWR0295")
					(unit 1)
				)
			)
		)
	)
	(symbol
		(lib_id "antmicropower:PWR_FLAG")
		(at 195.58 80.01 0)
		(unit 1)
		(exclude_from_sim no)
		(in_bom yes)
		(on_board yes)
		(dnp no)
		(property "Reference" "#FLG0123"
			(at 195.58 78.105 0)
			(effects
				(font
					(size 1.27 1.27)
				)
				(hide yes)
			)
		)
		(property "Value" "PWR_FLAG"
			(at 195.58 76.2 0)
			(effects
				(font
					(size 1.27 1.27)
				)
			)
		)
		(property "Footprint" ""
			(at 195.58 80.01 0)
			(effects
				(font
					(size 1.27 1.27)
				)
				(hide yes)
			)
		)
		(property "Datasheet" ""
			(at 195.58 80.01 0)
			(effects
				(font
					(size 1.27 1.27)
				)
				(hide yes)
			)
		)
		(property "Description" ""
			(at 195.58 80.01 0)
			(effects
				(font
					(size 1.27 1.27)
				)
				(hide yes)
			)
		)
		(pin "1"
		)
		(instances
			(project "artix-dc-scm"
				(path ""
					(reference "#FLG0123")
					(unit 1)
				)
			)
		)
	)
	(symbol
		(lib_id "antmicropower:GND")
		(at 171.45 87.63 0)
		(unit 1)
		(exclude_from_sim no)
		(in_bom yes)
		(on_board yes)
		(dnp no)
		(property "Reference" "#PWR0313"
			(at 171.45 93.98 0)
			(effects
				(font
					(size 1.27 1.27)
				)
				(hide yes)
			)
		)
		(property "Value" "GND"
			(at 171.45 91.44 0)
			(effects
				(font
					(size 1.27 1.27)
				)
			)
		)
		(property "Footprint" ""
			(at 171.45 87.63 0)
			(effects
				(font
					(size 1.27 1.27)
				)
				(hide yes)
			)
		)
		(property "Datasheet" ""
			(at 171.45 87.63 0)
			(effects
				(font
					(size 1.27 1.27)
				)
				(hide yes)
			)
		)
		(property "Description" ""
			(at 171.45 87.63 0)
			(effects
				(font
					(size 1.27 1.27)
				)
				(hide yes)
			)
		)
		(property "Author" "Antmicro"
			(at 180.34 95.25 0)
			(effects
				(font
					(size 1.27 1.27)
					(thickness 0.15)
				)
				(justify left bottom)
				(hide yes)
			)
		)
		(property "License" "Apache-2.0"
			(at 180.34 97.79 0)
			(effects
				(font
					(size 1.27 1.27)
					(thickness 0.15)
				)
				(justify left bottom)
				(hide yes)
			)
		)
		(pin "1"
		)
		(instances
			(project "artix-dc-scm"
				(path ""
					(reference "#PWR0313")
					(unit 1)
				)
			)
		)
	)
	(symbol
		(lib_id "antmicropower:GND")
		(at 101.6 203.2 0)
		(mirror y)
		(unit 1)
		(exclude_from_sim no)
		(in_bom yes)
		(on_board yes)
		(dnp no)
		(property "Reference" "#PWR0286"
			(at 101.6 209.55 0)
			(effects
				(font
					(size 1.27 1.27)
				)
				(hide yes)
			)
		)
		(property "Value" "GND"
			(at 101.6 207.01 0)
			(effects
				(font
					(size 1.27 1.27)
				)
			)
		)
		(property "Footprint" ""
			(at 101.6 203.2 0)
			(effects
				(font
					(size 1.27 1.27)
				)
				(hide yes)
			)
		)
		(property "Datasheet" ""
			(at 101.6 203.2 0)
			(effects
				(font
					(size 1.27 1.27)
				)
				(hide yes)
			)
		)
		(property "Description" ""
			(at 101.6 203.2 0)
			(effects
				(font
					(size 1.27 1.27)
				)
				(hide yes)
			)
		)
		(property "Author" "Antmicro"
			(at 92.71 210.82 0)
			(effects
				(font
					(size 1.27 1.27)
					(thickness 0.15)
				)
				(justify left bottom)
				(hide yes)
			)
		)
		(property "License" "Apache-2.0"
			(at 92.71 213.36 0)
			(effects
				(font
					(size 1.27 1.27)
					(thickness 0.15)
				)
				(justify left bottom)
				(hide yes)
			)
		)
		(pin "1"
		)
		(instances
			(project "artix-dc-scm"
				(path ""
					(reference "#PWR0286")
					(unit 1)
				)
			)
		)
	)
	(symbol
		(lib_id "antmicropower:GND")
		(at 64.77 63.5 0)
		(unit 1)
		(exclude_from_sim no)
		(in_bom yes)
		(on_board yes)
		(dnp no)
		(property "Reference" "#PWR0284"
			(at 64.77 69.85 0)
			(effects
				(font
					(size 1.27 1.27)
				)
				(hide yes)
			)
		)
		(property "Value" "GND"
			(at 64.77 67.31 0)
			(effects
				(font
					(size 1.27 1.27)
				)
			)
		)
		(property "Footprint" ""
			(at 64.77 63.5 0)
			(effects
				(font
					(size 1.27 1.27)
				)
				(hide yes)
			)
		)
		(property "Datasheet" ""
			(at 64.77 63.5 0)
			(effects
				(font
					(size 1.27 1.27)
				)
				(hide yes)
			)
		)
		(property "Description" ""
			(at 64.77 63.5 0)
			(effects
				(font
					(size 1.27 1.27)
				)
				(hide yes)
			)
		)
		(property "Author" "Antmicro"
			(at 73.66 71.12 0)
			(effects
				(font
					(size 1.27 1.27)
					(thickness 0.15)
				)
				(justify left bottom)
				(hide yes)
			)
		)
		(property "License" "Apache-2.0"
			(at 73.66 73.66 0)
			(effects
				(font
					(size 1.27 1.27)
					(thickness 0.15)
				)
				(justify left bottom)
				(hide yes)
			)
		)
		(pin "1"
		)
		(instances
			(project "artix-dc-scm"
				(path ""
					(reference "#PWR0284")
					(unit 1)
				)
			)
		)
	)
	(symbol
		(lib_id "antmicropower:GND")
		(at 316.23 74.93 0)
		(unit 1)
		(exclude_from_sim no)
		(in_bom yes)
		(on_board yes)
		(dnp no)
		(property "Reference" "#PWR0308"
			(at 316.23 81.28 0)
			(effects
				(font
					(size 1.27 1.27)
				)
				(hide yes)
			)
		)
		(property "Value" "GND"
			(at 316.23 78.74 0)
			(effects
				(font
					(size 1.27 1.27)
				)
			)
		)
		(property "Footprint" ""
			(at 316.23 74.93 0)
			(effects
				(font
					(size 1.27 1.27)
				)
				(hide yes)
			)
		)
		(property "Datasheet" ""
			(at 316.23 74.93 0)
			(effects
				(font
					(size 1.27 1.27)
				)
				(hide yes)
			)
		)
		(property "Description" ""
			(at 316.23 74.93 0)
			(effects
				(font
					(size 1.27 1.27)
				)
				(hide yes)
			)
		)
		(property "Author" "Antmicro"
			(at 325.12 82.55 0)
			(effects
				(font
					(size 1.27 1.27)
					(thickness 0.15)
				)
				(justify left bottom)
				(hide yes)
			)
		)
		(property "License" "Apache-2.0"
			(at 325.12 85.09 0)
			(effects
				(font
					(size 1.27 1.27)
					(thickness 0.15)
				)
				(justify left bottom)
				(hide yes)
			)
		)
		(pin "1"
		)
		(instances
			(project "artix-dc-scm"
				(path ""
					(reference "#PWR0308")
					(unit 1)
				)
			)
		)
	)
	(symbol
		(lib_id "antmicropower:GND")
		(at 316.23 208.28 0)
		(unit 1)
		(exclude_from_sim no)
		(in_bom yes)
		(on_board yes)
		(dnp no)
		(property "Reference" "#PWR0298"
			(at 316.23 214.63 0)
			(effects
				(font
					(size 1.27 1.27)
				)
				(hide yes)
			)
		)
		(property "Value" "GND"
			(at 316.23 212.09 0)
			(effects
				(font
					(size 1.27 1.27)
				)
			)
		)
		(property "Footprint" ""
			(at 316.23 208.28 0)
			(effects
				(font
					(size 1.27 1.27)
				)
				(hide yes)
			)
		)
		(property "Datasheet" ""
			(at 316.23 208.28 0)
			(effects
				(font
					(size 1.27 1.27)
				)
				(hide yes)
			)
		)
		(property "Description" ""
			(at 316.23 208.28 0)
			(effects
				(font
					(size 1.27 1.27)
				)
				(hide yes)
			)
		)
		(property "Author" "Antmicro"
			(at 325.12 215.9 0)
			(effects
				(font
					(size 1.27 1.27)
					(thickness 0.15)
				)
				(justify left bottom)
				(hide yes)
			)
		)
		(property "License" "Apache-2.0"
			(at 325.12 218.44 0)
			(effects
				(font
					(size 1.27 1.27)
					(thickness 0.15)
				)
				(justify left bottom)
				(hide yes)
			)
		)
		(pin "1"
		)
		(instances
			(project "artix-dc-scm"
				(path ""
					(reference "#PWR0298")
					(unit 1)
				)
			)
		)
	)
)
